(kicad_sch
	(version 20250114)
	(generator "eeschema")
	(generator_version "9.0")
	(paper "A3")
	(title_block
		(title "COM Express 7 Baseboard")
		(date "2025-02-04")
		(rev "1.1.2")
		(company "Antmicro Ltd")
		(comment 1 "www.antmicro.com")
	)
	(text "FR4 loss ~= 7.9dB/m/GHz; \n31.6 dB/m @ 4GHz\nfor 200 mm loss = 6.3 dB\nEQ[2:0] = 3'b101 gives 6.5 dB EQ @ 4 GHz\nFG[1:0] = 2'b10 for -0.5 dB (aiming for 0dB)\nSW1 = 1 for 1200 mVp-p swing\n "
		(exclude_from_sim no)
		(at 83.82 120.65 0)
		(effects
			(font
				(size 1.27 1.27)
			)
			(justify left bottom)
		)
	)
	(text "OCuLink 1m cable loss ~= 6.0 dB @ 4.5 GHz\nEQ[2:0] = 3'b101 gives 6.5 dB EQ @ 4 GHz\nFG[1:0] = 2'b10 for -0.5 dB (aiming for 0dB)\nSW1 = 1 for 1200 mVp-p swing\n "
		(exclude_from_sim no)
		(at 254 243.84 0)
		(effects
			(font
				(size 1.27 1.27)
			)
			(justify left bottom)
		)
	)
	(text "PCIe redriver"
		(exclude_from_sim no)
		(at 191.77 37.084 0)
		(effects
			(font
				(size 2 2)
				(thickness 0.8)
				(bold yes)
			)
			(justify left bottom)
		)
	)
	(junction
		(at 250.19 90.17)
		(diameter 0)
		(color 0 0 0 0)
	)
	(junction
		(at 247.65 229.87)
		(diameter 0)
		(color 0 0 0 0)
	)
	(junction
		(at 167.64 22.86)
		(diameter 0)
		(color 0 0 0 0)
	)
	(junction
		(at 149.86 38.1)
		(diameter 0)
		(color 0 0 0 0)
	)
	(junction
		(at 179.07 38.1)
		(diameter 0)
		(color 0 0 0 0)
	)
	(junction
		(at 245.11 254)
		(diameter 0)
		(color 0 0 0 0)
	)
	(junction
		(at 151.13 110.49)
		(diameter 0)
		(color 0 0 0 0)
	)
	(junction
		(at 237.49 254)
		(diameter 0)
		(color 0 0 0 0)
	)
	(junction
		(at 149.86 22.86)
		(diameter 0)
		(color 0 0 0 0)
	)
	(junction
		(at 146.05 129.54)
		(diameter 0)
		(color 0 0 0 0)
	)
	(junction
		(at 209.55 120.65)
		(diameter 0)
		(color 0 0 0 0)
	)
	(junction
		(at 156.21 118.11)
		(diameter 0)
		(color 0 0 0 0)
	)
	(junction
		(at 209.55 118.11)
		(diameter 0)
		(color 0 0 0 0)
	)
	(junction
		(at 148.59 107.95)
		(diameter 0)
		(color 0 0 0 0)
	)
	(junction
		(at 146.05 105.41)
		(diameter 0)
		(color 0 0 0 0)
	)
	(junction
		(at 245.11 232.41)
		(diameter 0)
		(color 0 0 0 0)
	)
	(junction
		(at 245.11 219.71)
		(diameter 0)
		(color 0 0 0 0)
	)
	(junction
		(at 240.03 219.71)
		(diameter 0)
		(color 0 0 0 0)
	)
	(junction
		(at 148.59 95.25)
		(diameter 0)
		(color 0 0 0 0)
	)
	(junction
		(at 156.21 129.54)
		(diameter 0)
		(color 0 0 0 0)
	)
	(junction
		(at 229.87 90.17)
		(diameter 0)
		(color 0 0 0 0)
	)
	(junction
		(at 170.18 160.02)
		(diameter 0)
		(color 0 0 0 0)
	)
	(junction
		(at 247.65 219.71)
		(diameter 0)
		(color 0 0 0 0)
	)
	(junction
		(at 240.03 240.03)
		(diameter 0)
		(color 0 0 0 0)
	)
	(junction
		(at 151.13 129.54)
		(diameter 0)
		(color 0 0 0 0)
	)
	(junction
		(at 179.07 144.78)
		(diameter 0)
		(color 0 0 0 0)
	)
	(junction
		(at 242.57 234.95)
		(diameter 0)
		(color 0 0 0 0)
	)
	(junction
		(at 184.15 245.11)
		(diameter 0)
		(color 0 0 0 0)
	)
	(junction
		(at 153.67 129.54)
		(diameter 0)
		(color 0 0 0 0)
	)
	(junction
		(at 237.49 219.71)
		(diameter 0)
		(color 0 0 0 0)
	)
	(junction
		(at 209.55 115.57)
		(diameter 0)
		(color 0 0 0 0)
	)
	(junction
		(at 148.59 129.54)
		(diameter 0)
		(color 0 0 0 0)
	)
	(junction
		(at 140.97 22.86)
		(diameter 0)
		(color 0 0 0 0)
	)
	(junction
		(at 153.67 115.57)
		(diameter 0)
		(color 0 0 0 0)
	)
	(junction
		(at 179.07 160.02)
		(diameter 0)
		(color 0 0 0 0)
	)
	(junction
		(at 132.08 22.86)
		(diameter 0)
		(color 0 0 0 0)
	)
	(junction
		(at 187.96 160.02)
		(diameter 0)
		(color 0 0 0 0)
	)
	(junction
		(at 247.65 254)
		(diameter 0)
		(color 0 0 0 0)
	)
	(junction
		(at 156.21 95.25)
		(diameter 0)
		(color 0 0 0 0)
	)
	(junction
		(at 184.15 240.03)
		(diameter 0)
		(color 0 0 0 0)
	)
	(junction
		(at 140.97 38.1)
		(diameter 0)
		(color 0 0 0 0)
	)
	(junction
		(at 152.4 144.78)
		(diameter 0)
		(color 0 0 0 0)
	)
	(junction
		(at 161.29 160.02)
		(diameter 0)
		(color 0 0 0 0)
	)
	(junction
		(at 237.49 242.57)
		(diameter 0)
		(color 0 0 0 0)
	)
	(junction
		(at 242.57 219.71)
		(diameter 0)
		(color 0 0 0 0)
	)
	(junction
		(at 199.39 160.02)
		(diameter 0)
		(color 0 0 0 0)
	)
	(junction
		(at 187.96 144.78)
		(diameter 0)
		(color 0 0 0 0)
	)
	(junction
		(at 167.64 38.1)
		(diameter 0)
		(color 0 0 0 0)
	)
	(junction
		(at 146.05 95.25)
		(diameter 0)
		(color 0 0 0 0)
	)
	(junction
		(at 184.15 242.57)
		(diameter 0)
		(color 0 0 0 0)
	)
	(junction
		(at 158.75 120.65)
		(diameter 0)
		(color 0 0 0 0)
	)
	(junction
		(at 153.67 95.25)
		(diameter 0)
		(color 0 0 0 0)
	)
	(junction
		(at 151.13 95.25)
		(diameter 0)
		(color 0 0 0 0)
	)
	(junction
		(at 158.75 38.1)
		(diameter 0)
		(color 0 0 0 0)
	)
	(junction
		(at 240.03 254)
		(diameter 0)
		(color 0 0 0 0)
	)
	(junction
		(at 234.95 245.11)
		(diameter 0)
		(color 0 0 0 0)
	)
	(junction
		(at 161.29 144.78)
		(diameter 0)
		(color 0 0 0 0)
	)
	(junction
		(at 170.18 144.78)
		(diameter 0)
		(color 0 0 0 0)
	)
	(junction
		(at 158.75 22.86)
		(diameter 0)
		(color 0 0 0 0)
	)
	(junction
		(at 242.57 254)
		(diameter 0)
		(color 0 0 0 0)
	)
	(bus_entry
		(at 259.08 60.96)
		(size -1.27 1.27)
		(stroke
			(width 0)
			(type default)
		)
	)
	(bus_entry
		(at 132.08 81.28)
		(size 1.27 1.27)
		(stroke
			(width 0)
			(type default)
		)
	)
	(bus_entry
		(at 132.08 60.96)
		(size 1.27 1.27)
		(stroke
			(width 0)
			(type default)
		)
	)
	(bus_entry
		(at 259.08 193.04)
		(size -1.27 1.27)
		(stroke
			(width 0)
			(type default)
		)
	)
	(bus_entry
		(at 259.08 81.28)
		(size -1.27 1.27)
		(stroke
			(width 0)
			(type default)
		)
	)
	(bus_entry
		(at 132.08 73.66)
		(size 1.27 1.27)
		(stroke
			(width 0)
			(type default)
		)
	)
	(bus_entry
		(at 259.08 205.74)
		(size -1.27 1.27)
		(stroke
			(width 0)
			(type default)
		)
	)
	(bus_entry
		(at 259.08 58.42)
		(size -1.27 1.27)
		(stroke
			(width 0)
			(type default)
		)
	)
	(bus_entry
		(at 259.08 198.12)
		(size -1.27 1.27)
		(stroke
			(width 0)
			(type default)
		)
	)
	(bus_entry
		(at 132.08 58.42)
		(size 1.27 1.27)
		(stroke
			(width 0)
			(type default)
		)
	)
	(bus_entry
		(at 259.08 68.58)
		(size -1.27 1.27)
		(stroke
			(width 0)
			(type default)
		)
	)
	(bus_entry
		(at 132.08 182.88)
		(size 1.27 1.27)
		(stroke
			(width 0)
			(type default)
		)
	)
	(bus_entry
		(at 132.08 76.2)
		(size 1.27 1.27)
		(stroke
			(width 0)
			(type default)
		)
	)
	(bus_entry
		(at 259.08 190.5)
		(size -1.27 1.27)
		(stroke
			(width 0)
			(type default)
		)
	)
	(bus_entry
		(at 132.08 200.66)
		(size 1.27 1.27)
		(stroke
			(width 0)
			(type default)
		)
	)
	(bus_entry
		(at 259.08 208.28)
		(size -1.27 1.27)
		(stroke
			(width 0)
			(type default)
		)
	)
	(bus_entry
		(at 132.08 68.58)
		(size 1.27 1.27)
		(stroke
			(width 0)
			(type default)
		)
	)
	(bus_entry
		(at 259.08 185.42)
		(size -1.27 1.27)
		(stroke
			(width 0)
			(type default)
		)
	)
	(bus_entry
		(at 259.08 76.2)
		(size -1.27 1.27)
		(stroke
			(width 0)
			(type default)
		)
	)
	(bus_entry
		(at 259.08 73.66)
		(size -1.27 1.27)
		(stroke
			(width 0)
			(type default)
		)
	)
	(bus_entry
		(at 259.08 182.88)
		(size -1.27 1.27)
		(stroke
			(width 0)
			(type default)
		)
	)
	(bus_entry
		(at 132.08 185.42)
		(size 1.27 1.27)
		(stroke
			(width 0)
			(type default)
		)
	)
	(bus_entry
		(at 132.08 83.82)
		(size 1.27 1.27)
		(stroke
			(width 0)
			(type default)
		)
	)
	(bus_entry
		(at 259.08 66.04)
		(size -1.27 1.27)
		(stroke
			(width 0)
			(type default)
		)
	)
	(bus_entry
		(at 259.08 200.66)
		(size -1.27 1.27)
		(stroke
			(width 0)
			(type default)
		)
	)
	(bus_entry
		(at 132.08 208.28)
		(size 1.27 1.27)
		(stroke
			(width 0)
			(type default)
		)
	)
	(bus_entry
		(at 132.08 205.74)
		(size 1.27 1.27)
		(stroke
			(width 0)
			(type default)
		)
	)
	(bus_entry
		(at 132.08 193.04)
		(size 1.27 1.27)
		(stroke
			(width 0)
			(type default)
		)
	)
	(bus_entry
		(at 132.08 198.12)
		(size 1.27 1.27)
		(stroke
			(width 0)
			(type default)
		)
	)
	(bus_entry
		(at 259.08 83.82)
		(size -1.27 1.27)
		(stroke
			(width 0)
			(type default)
		)
	)
	(bus_entry
		(at 132.08 190.5)
		(size 1.27 1.27)
		(stroke
			(width 0)
			(type default)
		)
	)
	(bus_entry
		(at 132.08 66.04)
		(size 1.27 1.27)
		(stroke
			(width 0)
			(type default)
		)
	)
	(wire
		(pts
			(xy 210.82 222.25) (xy 208.28 222.25)
		)
		(stroke
			(width 0)
			(type default)
		)
	)
	(wire
		(pts
			(xy 182.88 100.33) (xy 185.42 100.33)
		)
		(stroke
			(width 0)
			(type default)
		)
	)
	(wire
		(pts
			(xy 156.21 95.25) (xy 153.67 95.25)
		)
		(stroke
			(width 0)
			(type default)
		)
	)
	(wire
		(pts
			(xy 234.95 85.09) (xy 257.81 85.09)
		)
		(stroke
			(width 0)
			(type default)
		)
	)
	(wire
		(pts
			(xy 149.86 38.1) (xy 149.86 40.64)
		)
		(stroke
			(width 0)
			(type default)
		)
	)
	(wire
		(pts
			(xy 148.59 127) (xy 148.59 129.54)
		)
		(stroke
			(width 0)
			(type default)
		)
	)
	(wire
		(pts
			(xy 240.03 219.71) (xy 240.03 222.25)
		)
		(stroke
			(width 0)
			(type default)
		)
	)
	(wire
		(pts
			(xy 247.65 254) (xy 250.19 254)
		)
		(stroke
			(width 0)
			(type default)
		)
	)
	(bus
		(pts
			(xy 132.08 200.66) (xy 132.08 205.74)
		)
		(stroke
			(width 0)
			(type default)
		)
	)
	(wire
		(pts
			(xy 208.28 201.93) (xy 257.81 201.93)
		)
		(stroke
			(width 0)
			(type default)
		)
	)
	(wire
		(pts
			(xy 133.35 199.39) (xy 154.94 199.39)
		)
		(stroke
			(width 0)
			(type default)
		)
	)
	(wire
		(pts
			(xy 214.63 179.07) (xy 208.28 179.07)
		)
		(stroke
			(width 0)
			(type default)
		)
	)
	(wire
		(pts
			(xy 209.55 113.03) (xy 209.55 115.57)
		)
		(stroke
			(width 0)
			(type default)
		)
	)
	(wire
		(pts
			(xy 158.75 40.64) (xy 158.75 38.1)
		)
		(stroke
			(width 0)
			(type default)
		)
	)
	(wire
		(pts
			(xy 242.57 219.71) (xy 245.11 219.71)
		)
		(stroke
			(width 0)
			(type default)
		)
	)
	(wire
		(pts
			(xy 199.39 160.02) (xy 199.39 144.78)
		)
		(stroke
			(width 0)
			(type default)
		)
	)
	(wire
		(pts
			(xy 153.67 127) (xy 153.67 129.54)
		)
		(stroke
			(width 0)
			(type default)
		)
	)
	(wire
		(pts
			(xy 146.05 105.41) (xy 146.05 102.87)
		)
		(stroke
			(width 0)
			(type default)
		)
	)
	(wire
		(pts
			(xy 158.75 120.65) (xy 158.75 102.87)
		)
		(stroke
			(width 0)
			(type default)
		)
	)
	(wire
		(pts
			(xy 133.35 67.31) (xy 185.42 67.31)
		)
		(stroke
			(width 0)
			(type default)
		)
	)
	(wire
		(pts
			(xy 157.48 194.31) (xy 185.42 194.31)
		)
		(stroke
			(width 0)
			(type default)
		)
	)
	(wire
		(pts
			(xy 184.15 242.57) (xy 184.15 240.03)
		)
		(stroke
			(width 0)
			(type default)
		)
	)
	(wire
		(pts
			(xy 148.59 107.95) (xy 148.59 121.92)
		)
		(stroke
			(width 0)
			(type default)
		)
	)
	(wire
		(pts
			(xy 209.55 120.65) (xy 208.28 120.65)
		)
		(stroke
			(width 0)
			(type default)
		)
	)
	(wire
		(pts
			(xy 146.05 95.25) (xy 143.51 95.25)
		)
		(stroke
			(width 0)
			(type default)
		)
	)
	(wire
		(pts
			(xy 247.65 251.46) (xy 247.65 254)
		)
		(stroke
			(width 0)
			(type default)
		)
	)
	(wire
		(pts
			(xy 237.49 227.33) (xy 237.49 242.57)
		)
		(stroke
			(width 0)
			(type default)
		)
	)
	(wire
		(pts
			(xy 234.95 245.11) (xy 234.95 227.33)
		)
		(stroke
			(width 0)
			(type default)
		)
	)
	(wire
		(pts
			(xy 234.95 222.25) (xy 234.95 219.71)
		)
		(stroke
			(width 0)
			(type default)
		)
	)
	(wire
		(pts
			(xy 132.08 21.59) (xy 132.08 22.86)
		)
		(stroke
			(width 0)
			(type default)
		)
	)
	(wire
		(pts
			(xy 185.42 242.57) (xy 184.15 242.57)
		)
		(stroke
			(width 0)
			(type default)
		)
	)
	(wire
		(pts
			(xy 240.03 254) (xy 237.49 254)
		)
		(stroke
			(width 0)
			(type default)
		)
	)
	(wire
		(pts
			(xy 208.28 69.85) (xy 229.87 69.85)
		)
		(stroke
			(width 0)
			(type default)
		)
	)
	(wire
		(pts
			(xy 148.59 95.25) (xy 146.05 95.25)
		)
		(stroke
			(width 0)
			(type default)
		)
	)
	(wire
		(pts
			(xy 157.48 201.93) (xy 185.42 201.93)
		)
		(stroke
			(width 0)
			(type default)
		)
	)
	(wire
		(pts
			(xy 156.21 95.25) (xy 156.21 97.79)
		)
		(stroke
			(width 0)
			(type default)
		)
	)
	(bus
		(pts
			(xy 132.08 68.58) (xy 132.08 73.66)
		)
		(stroke
			(width 0)
			(type default)
		)
	)
	(bus
		(pts
			(xy 132.08 190.5) (xy 132.08 193.04)
		)
		(stroke
			(width 0)
			(type default)
		)
	)
	(wire
		(pts
			(xy 151.13 129.54) (xy 153.67 129.54)
		)
		(stroke
			(width 0)
			(type default)
		)
	)
	(wire
		(pts
			(xy 152.4 160.02) (xy 161.29 160.02)
		)
		(stroke
			(width 0)
			(type default)
		)
	)
	(bus
		(pts
			(xy 259.08 198.12) (xy 259.08 200.66)
		)
		(stroke
			(width 0)
			(type default)
		)
	)
	(wire
		(pts
			(xy 208.28 191.77) (xy 257.81 191.77)
		)
		(stroke
			(width 0)
			(type default)
		)
	)
	(wire
		(pts
			(xy 182.88 90.17) (xy 185.42 90.17)
		)
		(stroke
			(width 0)
			(type default)
		)
	)
	(wire
		(pts
			(xy 153.67 95.25) (xy 151.13 95.25)
		)
		(stroke
			(width 0)
			(type default)
		)
	)
	(bus
		(pts
			(xy 259.08 190.5) (xy 259.08 193.04)
		)
		(stroke
			(width 0)
			(type default)
		)
	)
	(wire
		(pts
			(xy 156.21 127) (xy 156.21 129.54)
		)
		(stroke
			(width 0)
			(type default)
		)
	)
	(wire
		(pts
			(xy 247.65 219.71) (xy 247.65 222.25)
		)
		(stroke
			(width 0)
			(type default)
		)
	)
	(wire
		(pts
			(xy 187.96 144.78) (xy 187.96 147.32)
		)
		(stroke
			(width 0)
			(type default)
		)
	)
	(wire
		(pts
			(xy 250.19 217.17) (xy 250.19 219.71)
		)
		(stroke
			(width 0)
			(type default)
		)
	)
	(bus
		(pts
			(xy 132.08 193.04) (xy 132.08 198.12)
		)
		(stroke
			(width 0)
			(type default)
		)
	)
	(wire
		(pts
			(xy 229.87 90.17) (xy 250.19 90.17)
		)
		(stroke
			(width 0)
			(type default)
		)
	)
	(wire
		(pts
			(xy 160.02 207.01) (xy 185.42 207.01)
		)
		(stroke
			(width 0)
			(type default)
		)
	)
	(bus
		(pts
			(xy 132.08 55.88) (xy 132.08 58.42)
		)
		(stroke
			(width 0)
			(type default)
		)
	)
	(bus
		(pts
			(xy 132.08 83.82) (xy 132.08 182.88)
		)
		(stroke
			(width 0)
			(type default)
		)
	)
	(wire
		(pts
			(xy 184.15 242.57) (xy 184.15 245.11)
		)
		(stroke
			(width 0)
			(type default)
		)
	)
	(wire
		(pts
			(xy 250.19 254) (xy 250.19 256.54)
		)
		(stroke
			(width 0)
			(type default)
		)
	)
	(wire
		(pts
			(xy 247.65 229.87) (xy 247.65 246.38)
		)
		(stroke
			(width 0)
			(type default)
		)
	)
	(bus
		(pts
			(xy 259.08 76.2) (xy 259.08 81.28)
		)
		(stroke
			(width 0)
			(type default)
		)
	)
	(wire
		(pts
			(xy 179.07 54.61) (xy 185.42 54.61)
		)
		(stroke
			(width 0)
			(type default)
		)
	)
	(wire
		(pts
			(xy 185.42 105.41) (xy 146.05 105.41)
		)
		(stroke
			(width 0)
			(type default)
		)
	)
	(wire
		(pts
			(xy 152.4 144.78) (xy 161.29 144.78)
		)
		(stroke
			(width 0)
			(type default)
		)
	)
	(bus
		(pts
			(xy 259.08 182.88) (xy 259.08 185.42)
		)
		(stroke
			(width 0)
			(type default)
		)
	)
	(wire
		(pts
			(xy 215.9 95.25) (xy 215.9 93.98)
		)
		(stroke
			(width 0)
			(type default)
		)
	)
	(wire
		(pts
			(xy 132.08 25.4) (xy 132.08 22.86)
		)
		(stroke
			(width 0)
			(type default)
		)
	)
	(bus
		(pts
			(xy 132.08 73.66) (xy 132.08 76.2)
		)
		(stroke
			(width 0)
			(type default)
		)
	)
	(bus
		(pts
			(xy 259.08 73.66) (xy 259.08 76.2)
		)
		(stroke
			(width 0)
			(type default)
		)
	)
	(bus
		(pts
			(xy 259.08 185.42) (xy 259.08 190.5)
		)
		(stroke
			(width 0)
			(type default)
		)
	)
	(wire
		(pts
			(xy 242.57 254) (xy 240.03 254)
		)
		(stroke
			(width 0)
			(type default)
		)
	)
	(wire
		(pts
			(xy 214.63 160.02) (xy 214.63 179.07)
		)
		(stroke
			(width 0)
			(type default)
		)
	)
	(wire
		(pts
			(xy 179.07 162.56) (xy 179.07 160.02)
		)
		(stroke
			(width 0)
			(type default)
		)
	)
	(wire
		(pts
			(xy 229.87 90.17) (xy 229.87 91.44)
		)
		(stroke
			(width 0)
			(type default)
		)
	)
	(wire
		(pts
			(xy 148.59 95.25) (xy 148.59 97.79)
		)
		(stroke
			(width 0)
			(type default)
		)
	)
	(wire
		(pts
			(xy 158.75 25.4) (xy 158.75 22.86)
		)
		(stroke
			(width 0)
			(type default)
		)
	)
	(bus
		(pts
			(xy 259.08 193.04) (xy 259.08 198.12)
		)
		(stroke
			(width 0)
			(type default)
		)
	)
	(wire
		(pts
			(xy 240.03 240.03) (xy 240.03 246.38)
		)
		(stroke
			(width 0)
			(type default)
		)
	)
	(wire
		(pts
			(xy 132.08 40.64) (xy 132.08 38.1)
		)
		(stroke
			(width 0)
			(type default)
		)
	)
	(wire
		(pts
			(xy 179.07 160.02) (xy 187.96 160.02)
		)
		(stroke
			(width 0)
			(type default)
		)
	)
	(wire
		(pts
			(xy 209.55 115.57) (xy 208.28 115.57)
		)
		(stroke
			(width 0)
			(type default)
		)
	)
	(wire
		(pts
			(xy 237.49 59.69) (xy 257.81 59.69)
		)
		(stroke
			(width 0)
			(type default)
		)
	)
	(wire
		(pts
			(xy 185.42 237.49) (xy 184.15 237.49)
		)
		(stroke
			(width 0)
			(type default)
		)
	)
	(wire
		(pts
			(xy 133.35 194.31) (xy 152.4 194.31)
		)
		(stroke
			(width 0)
			(type default)
		)
	)
	(bus
		(pts
			(xy 132.08 205.74) (xy 132.08 208.28)
		)
		(stroke
			(width 0)
			(type default)
		)
	)
	(wire
		(pts
			(xy 165.1 96.52) (xy 165.1 95.25)
		)
		(stroke
			(width 0)
			(type default)
		)
	)
	(wire
		(pts
			(xy 208.28 59.69) (xy 232.41 59.69)
		)
		(stroke
			(width 0)
			(type default)
		)
	)
	(wire
		(pts
			(xy 165.1 95.25) (xy 166.37 95.25)
		)
		(stroke
			(width 0)
			(type default)
		)
	)
	(wire
		(pts
			(xy 214.63 95.25) (xy 215.9 95.25)
		)
		(stroke
			(width 0)
			(type default)
		)
	)
	(wire
		(pts
			(xy 208.28 207.01) (xy 257.81 207.01)
		)
		(stroke
			(width 0)
			(type default)
		)
	)
	(bus
		(pts
			(xy 259.08 60.96) (xy 259.08 66.04)
		)
		(stroke
			(width 0)
			(type default)
		)
	)
	(wire
		(pts
			(xy 143.51 129.54) (xy 143.51 132.08)
		)
		(stroke
			(width 0)
			(type default)
		)
	)
	(wire
		(pts
			(xy 170.18 144.78) (xy 170.18 147.32)
		)
		(stroke
			(width 0)
			(type default)
		)
	)
	(wire
		(pts
			(xy 140.97 38.1) (xy 149.86 38.1)
		)
		(stroke
			(width 0)
			(type default)
		)
	)
	(wire
		(pts
			(xy 158.75 97.79) (xy 158.75 95.25)
		)
		(stroke
			(width 0)
			(type default)
		)
	)
	(wire
		(pts
			(xy 247.65 254) (xy 245.11 254)
		)
		(stroke
			(width 0)
			(type default)
		)
	)
	(wire
		(pts
			(xy 208.28 199.39) (xy 257.81 199.39)
		)
		(stroke
			(width 0)
			(type default)
		)
	)
	(wire
		(pts
			(xy 237.49 219.71) (xy 237.49 222.25)
		)
		(stroke
			(width 0)
			(type default)
		)
	)
	(wire
		(pts
			(xy 237.49 242.57) (xy 208.28 242.57)
		)
		(stroke
			(width 0)
			(type default)
		)
	)
	(wire
		(pts
			(xy 208.28 95.25) (xy 209.55 95.25)
		)
		(stroke
			(width 0)
			(type default)
		)
	)
	(wire
		(pts
			(xy 182.88 97.79) (xy 185.42 97.79)
		)
		(stroke
			(width 0)
			(type default)
		)
	)
	(wire
		(pts
			(xy 133.35 85.09) (xy 185.42 85.09)
		)
		(stroke
			(width 0)
			(type default)
		)
	)
	(wire
		(pts
			(xy 208.28 234.95) (xy 242.57 234.95)
		)
		(stroke
			(width 0)
			(type default)
		)
	)
	(wire
		(pts
			(xy 161.29 144.78) (xy 170.18 144.78)
		)
		(stroke
			(width 0)
			(type default)
		)
	)
	(wire
		(pts
			(xy 208.28 186.69) (xy 257.81 186.69)
		)
		(stroke
			(width 0)
			(type default)
		)
	)
	(wire
		(pts
			(xy 208.28 184.15) (xy 257.81 184.15)
		)
		(stroke
			(width 0)
			(type default)
		)
	)
	(wire
		(pts
			(xy 153.67 115.57) (xy 153.67 102.87)
		)
		(stroke
			(width 0)
			(type default)
		)
	)
	(wire
		(pts
			(xy 133.35 77.47) (xy 185.42 77.47)
		)
		(stroke
			(width 0)
			(type default)
		)
	)
	(wire
		(pts
			(xy 242.57 234.95) (xy 242.57 246.38)
		)
		(stroke
			(width 0)
			(type default)
		)
	)
	(wire
		(pts
			(xy 247.65 219.71) (xy 250.19 219.71)
		)
		(stroke
			(width 0)
			(type default)
		)
	)
	(wire
		(pts
			(xy 237.49 82.55) (xy 257.81 82.55)
		)
		(stroke
			(width 0)
			(type default)
		)
	)
	(wire
		(pts
			(xy 228.6 219.71) (xy 227.33 219.71)
		)
		(stroke
			(width 0)
			(type default)
		)
	)
	(wire
		(pts
			(xy 240.03 251.46) (xy 240.03 254)
		)
		(stroke
			(width 0)
			(type default)
		)
	)
	(wire
		(pts
			(xy 132.08 38.1) (xy 140.97 38.1)
		)
		(stroke
			(width 0)
			(type default)
		)
	)
	(wire
		(pts
			(xy 182.88 92.71) (xy 185.42 92.71)
		)
		(stroke
			(width 0)
			(type default)
		)
	)
	(wire
		(pts
			(xy 179.07 147.32) (xy 179.07 144.78)
		)
		(stroke
			(width 0)
			(type default)
		)
	)
	(wire
		(pts
			(xy 149.86 38.1) (xy 158.75 38.1)
		)
		(stroke
			(width 0)
			(type default)
		)
	)
	(bus
		(pts
			(xy 259.08 83.82) (xy 259.08 182.88)
		)
		(stroke
			(width 0)
			(type default)
		)
	)
	(wire
		(pts
			(xy 185.42 115.57) (xy 153.67 115.57)
		)
		(stroke
			(width 0)
			(type default)
		)
	)
	(wire
		(pts
			(xy 140.97 38.1) (xy 140.97 40.64)
		)
		(stroke
			(width 0)
			(type default)
		)
	)
	(wire
		(pts
			(xy 208.28 67.31) (xy 232.41 67.31)
		)
		(stroke
			(width 0)
			(type default)
		)
	)
	(wire
		(pts
			(xy 234.95 251.46) (xy 234.95 254)
		)
		(stroke
			(width 0)
			(type default)
		)
	)
	(wire
		(pts
			(xy 157.48 209.55) (xy 185.42 209.55)
		)
		(stroke
			(width 0)
			(type default)
		)
	)
	(wire
		(pts
			(xy 237.49 219.71) (xy 240.03 219.71)
		)
		(stroke
			(width 0)
			(type default)
		)
	)
	(wire
		(pts
			(xy 148.59 129.54) (xy 151.13 129.54)
		)
		(stroke
			(width 0)
			(type default)
		)
	)
	(wire
		(pts
			(xy 237.49 67.31) (xy 257.81 67.31)
		)
		(stroke
			(width 0)
			(type default)
		)
	)
	(wire
		(pts
			(xy 187.96 160.02) (xy 187.96 162.56)
		)
		(stroke
			(width 0)
			(type default)
		)
	)
	(wire
		(pts
			(xy 210.82 224.79) (xy 208.28 224.79)
		)
		(stroke
			(width 0)
			(type default)
		)
	)
	(bus
		(pts
			(xy 132.08 198.12) (xy 132.08 200.66)
		)
		(stroke
			(width 0)
			(type default)
		)
	)
	(wire
		(pts
			(xy 156.21 118.11) (xy 156.21 121.92)
		)
		(stroke
			(width 0)
			(type default)
		)
	)
	(wire
		(pts
			(xy 208.28 118.11) (xy 209.55 118.11)
		)
		(stroke
			(width 0)
			(type default)
		)
	)
	(wire
		(pts
			(xy 209.55 118.11) (xy 209.55 120.65)
		)
		(stroke
			(width 0)
			(type default)
		)
	)
	(wire
		(pts
			(xy 247.65 229.87) (xy 247.65 227.33)
		)
		(stroke
			(width 0)
			(type default)
		)
	)
	(wire
		(pts
			(xy 210.82 217.17) (xy 208.28 217.17)
		)
		(stroke
			(width 0)
			(type default)
		)
	)
	(wire
		(pts
			(xy 171.45 95.25) (xy 185.42 95.25)
		)
		(stroke
			(width 0)
			(type default)
		)
	)
	(wire
		(pts
			(xy 158.75 120.65) (xy 158.75 121.92)
		)
		(stroke
			(width 0)
			(type default)
		)
	)
	(wire
		(pts
			(xy 245.11 254) (xy 242.57 254)
		)
		(stroke
			(width 0)
			(type default)
		)
	)
	(wire
		(pts
			(xy 237.49 251.46) (xy 237.49 254)
		)
		(stroke
			(width 0)
			(type default)
		)
	)
	(wire
		(pts
			(xy 143.51 92.71) (xy 143.51 95.25)
		)
		(stroke
			(width 0)
			(type default)
		)
	)
	(bus
		(pts
			(xy 132.08 60.96) (xy 132.08 66.04)
		)
		(stroke
			(width 0)
			(type default)
		)
	)
	(wire
		(pts
			(xy 185.42 219.71) (xy 184.15 219.71)
		)
		(stroke
			(width 0)
			(type default)
		)
	)
	(wire
		(pts
			(xy 208.28 209.55) (xy 257.81 209.55)
		)
		(stroke
			(width 0)
			(type default)
		)
	)
	(wire
		(pts
			(xy 184.15 240.03) (xy 185.42 240.03)
		)
		(stroke
			(width 0)
			(type default)
		)
	)
	(wire
		(pts
			(xy 181.61 214.63) (xy 181.61 175.26)
		)
		(stroke
			(width 0)
			(type default)
		)
	)
	(wire
		(pts
			(xy 242.57 219.71) (xy 242.57 222.25)
		)
		(stroke
			(width 0)
			(type default)
		)
	)
	(wire
		(pts
			(xy 222.25 219.71) (xy 208.28 219.71)
		)
		(stroke
			(width 0)
			(type default)
		)
	)
	(wire
		(pts
			(xy 146.05 129.54) (xy 143.51 129.54)
		)
		(stroke
			(width 0)
			(type default)
		)
	)
	(wire
		(pts
			(xy 152.4 162.56) (xy 152.4 160.02)
		)
		(stroke
			(width 0)
			(type default)
		)
	)
	(wire
		(pts
			(xy 160.02 184.15) (xy 185.42 184.15)
		)
		(stroke
			(width 0)
			(type default)
		)
	)
	(wire
		(pts
			(xy 161.29 144.78) (xy 161.29 147.32)
		)
		(stroke
			(width 0)
			(type default)
		)
	)
	(wire
		(pts
			(xy 156.21 129.54) (xy 158.75 129.54)
		)
		(stroke
			(width 0)
			(type default)
		)
	)
	(wire
		(pts
			(xy 133.35 69.85) (xy 185.42 69.85)
		)
		(stroke
			(width 0)
			(type default)
		)
	)
	(wire
		(pts
			(xy 184.15 237.49) (xy 184.15 240.03)
		)
		(stroke
			(width 0)
			(type default)
		)
	)
	(wire
		(pts
			(xy 210.82 214.63) (xy 208.28 214.63)
		)
		(stroke
			(width 0)
			(type default)
		)
	)
	(wire
		(pts
			(xy 148.59 102.87) (xy 148.59 107.95)
		)
		(stroke
			(width 0)
			(type default)
		)
	)
	(wire
		(pts
			(xy 184.15 245.11) (xy 185.42 245.11)
		)
		(stroke
			(width 0)
			(type default)
		)
	)
	(wire
		(pts
			(xy 158.75 22.86) (xy 167.64 22.86)
		)
		(stroke
			(width 0)
			(type default)
		)
	)
	(wire
		(pts
			(xy 237.49 254) (xy 234.95 254)
		)
		(stroke
			(width 0)
			(type default)
		)
	)
	(wire
		(pts
			(xy 160.02 191.77) (xy 185.42 191.77)
		)
		(stroke
			(width 0)
			(type default)
		)
	)
	(wire
		(pts
			(xy 151.13 95.25) (xy 148.59 95.25)
		)
		(stroke
			(width 0)
			(type default)
		)
	)
	(bus
		(pts
			(xy 259.08 55.88) (xy 260.35 54.61)
		)
		(stroke
			(width 0)
			(type default)
		)
	)
	(wire
		(pts
			(xy 208.28 245.11) (xy 234.95 245.11)
		)
		(stroke
			(width 0)
			(type default)
		)
	)
	(wire
		(pts
			(xy 146.05 127) (xy 146.05 129.54)
		)
		(stroke
			(width 0)
			(type default)
		)
	)
	(wire
		(pts
			(xy 170.18 160.02) (xy 170.18 162.56)
		)
		(stroke
			(width 0)
			(type default)
		)
	)
	(wire
		(pts
			(xy 149.86 22.86) (xy 158.75 22.86)
		)
		(stroke
			(width 0)
			(type default)
		)
	)
	(wire
		(pts
			(xy 158.75 95.25) (xy 156.21 95.25)
		)
		(stroke
			(width 0)
			(type default)
		)
	)
	(wire
		(pts
			(xy 153.67 129.54) (xy 156.21 129.54)
		)
		(stroke
			(width 0)
			(type default)
		)
	)
	(bus
		(pts
			(xy 124.46 54.61) (xy 130.81 54.61)
		)
		(stroke
			(width 0)
			(type default)
		)
	)
	(wire
		(pts
			(xy 208.28 194.31) (xy 257.81 194.31)
		)
		(stroke
			(width 0)
			(type default)
		)
	)
	(wire
		(pts
			(xy 240.03 240.03) (xy 240.03 227.33)
		)
		(stroke
			(width 0)
			(type default)
		)
	)
	(wire
		(pts
			(xy 208.28 77.47) (xy 229.87 77.47)
		)
		(stroke
			(width 0)
			(type default)
		)
	)
	(wire
		(pts
			(xy 209.55 123.19) (xy 209.55 120.65)
		)
		(stroke
			(width 0)
			(type default)
		)
	)
	(wire
		(pts
			(xy 146.05 105.41) (xy 146.05 121.92)
		)
		(stroke
			(width 0)
			(type default)
		)
	)
	(wire
		(pts
			(xy 240.03 219.71) (xy 242.57 219.71)
		)
		(stroke
			(width 0)
			(type default)
		)
	)
	(bus
		(pts
			(xy 266.7 54.61) (xy 260.35 54.61)
		)
		(stroke
			(width 0)
			(type default)
		)
	)
	(wire
		(pts
			(xy 140.97 22.86) (xy 140.97 25.4)
		)
		(stroke
			(width 0)
			(type default)
		)
	)
	(bus
		(pts
			(xy 132.08 185.42) (xy 132.08 190.5)
		)
		(stroke
			(width 0)
			(type default)
		)
	)
	(wire
		(pts
			(xy 133.35 184.15) (xy 154.94 184.15)
		)
		(stroke
			(width 0)
			(type default)
		)
	)
	(wire
		(pts
			(xy 242.57 251.46) (xy 242.57 254)
		)
		(stroke
			(width 0)
			(type default)
		)
	)
	(wire
		(pts
			(xy 208.28 74.93) (xy 232.41 74.93)
		)
		(stroke
			(width 0)
			(type default)
		)
	)
	(bus
		(pts
			(xy 259.08 66.04) (xy 259.08 68.58)
		)
		(stroke
			(width 0)
			(type default)
		)
	)
	(wire
		(pts
			(xy 208.28 229.87) (xy 247.65 229.87)
		)
		(stroke
			(width 0)
			(type default)
		)
	)
	(wire
		(pts
			(xy 185.42 120.65) (xy 158.75 120.65)
		)
		(stroke
			(width 0)
			(type default)
		)
	)
	(bus
		(pts
			(xy 259.08 55.88) (xy 259.08 58.42)
		)
		(stroke
			(width 0)
			(type default)
		)
	)
	(wire
		(pts
			(xy 133.35 59.69) (xy 185.42 59.69)
		)
		(stroke
			(width 0)
			(type default)
		)
	)
	(wire
		(pts
			(xy 146.05 95.25) (xy 146.05 97.79)
		)
		(stroke
			(width 0)
			(type default)
		)
	)
	(wire
		(pts
			(xy 152.4 147.32) (xy 152.4 144.78)
		)
		(stroke
			(width 0)
			(type default)
		)
	)
	(bus
		(pts
			(xy 132.08 76.2) (xy 132.08 81.28)
		)
		(stroke
			(width 0)
			(type default)
		)
	)
	(wire
		(pts
			(xy 170.18 144.78) (xy 179.07 144.78)
		)
		(stroke
			(width 0)
			(type default)
		)
	)
	(wire
		(pts
			(xy 185.42 214.63) (xy 181.61 214.63)
		)
		(stroke
			(width 0)
			(type default)
		)
	)
	(wire
		(pts
			(xy 161.29 160.02) (xy 161.29 162.56)
		)
		(stroke
			(width 0)
			(type default)
		)
	)
	(wire
		(pts
			(xy 151.13 127) (xy 151.13 129.54)
		)
		(stroke
			(width 0)
			(type default)
		)
	)
	(wire
		(pts
			(xy 151.13 110.49) (xy 151.13 121.92)
		)
		(stroke
			(width 0)
			(type default)
		)
	)
	(wire
		(pts
			(xy 245.11 251.46) (xy 245.11 254)
		)
		(stroke
			(width 0)
			(type default)
		)
	)
	(wire
		(pts
			(xy 157.48 186.69) (xy 185.42 186.69)
		)
		(stroke
			(width 0)
			(type default)
		)
	)
	(wire
		(pts
			(xy 160.02 199.39) (xy 185.42 199.39)
		)
		(stroke
			(width 0)
			(type default)
		)
	)
	(wire
		(pts
			(xy 250.19 90.17) (xy 266.7 90.17)
		)
		(stroke
			(width 0)
			(type default)
		)
	)
	(wire
		(pts
			(xy 177.8 219.71) (xy 177.8 218.44)
		)
		(stroke
			(width 0)
			(type default)
		)
	)
	(wire
		(pts
			(xy 179.07 144.78) (xy 187.96 144.78)
		)
		(stroke
			(width 0)
			(type default)
		)
	)
	(wire
		(pts
			(xy 133.35 82.55) (xy 185.42 82.55)
		)
		(stroke
			(width 0)
			(type default)
		)
	)
	(bus
		(pts
			(xy 132.08 182.88) (xy 132.08 185.42)
		)
		(stroke
			(width 0)
			(type default)
		)
	)
	(wire
		(pts
			(xy 185.42 110.49) (xy 151.13 110.49)
		)
		(stroke
			(width 0)
			(type default)
		)
	)
	(wire
		(pts
			(xy 179.07 38.1) (xy 179.07 22.86)
		)
		(stroke
			(width 0)
			(type default)
		)
	)
	(bus
		(pts
			(xy 259.08 200.66) (xy 259.08 205.74)
		)
		(stroke
			(width 0)
			(type default)
		)
	)
	(wire
		(pts
			(xy 133.35 191.77) (xy 154.94 191.77)
		)
		(stroke
			(width 0)
			(type default)
		)
	)
	(wire
		(pts
			(xy 133.35 209.55) (xy 152.4 209.55)
		)
		(stroke
			(width 0)
			(type default)
		)
	)
	(wire
		(pts
			(xy 187.96 160.02) (xy 199.39 160.02)
		)
		(stroke
			(width 0)
			(type default)
		)
	)
	(wire
		(pts
			(xy 245.11 227.33) (xy 245.11 232.41)
		)
		(stroke
			(width 0)
			(type default)
		)
	)
	(wire
		(pts
			(xy 133.35 62.23) (xy 185.42 62.23)
		)
		(stroke
			(width 0)
			(type default)
		)
	)
	(wire
		(pts
			(xy 167.64 38.1) (xy 167.64 40.64)
		)
		(stroke
			(width 0)
			(type default)
		)
	)
	(wire
		(pts
			(xy 158.75 38.1) (xy 167.64 38.1)
		)
		(stroke
			(width 0)
			(type default)
		)
	)
	(wire
		(pts
			(xy 228.6 220.98) (xy 228.6 219.71)
		)
		(stroke
			(width 0)
			(type default)
		)
	)
	(wire
		(pts
			(xy 152.4 143.51) (xy 152.4 144.78)
		)
		(stroke
			(width 0)
			(type default)
		)
	)
	(bus
		(pts
			(xy 259.08 68.58) (xy 259.08 73.66)
		)
		(stroke
			(width 0)
			(type default)
		)
	)
	(wire
		(pts
			(xy 153.67 115.57) (xy 153.67 121.92)
		)
		(stroke
			(width 0)
			(type default)
		)
	)
	(bus
		(pts
			(xy 259.08 81.28) (xy 259.08 83.82)
		)
		(stroke
			(width 0)
			(type default)
		)
	)
	(wire
		(pts
			(xy 132.08 22.86) (xy 140.97 22.86)
		)
		(stroke
			(width 0)
			(type default)
		)
	)
	(wire
		(pts
			(xy 245.11 232.41) (xy 245.11 246.38)
		)
		(stroke
			(width 0)
			(type default)
		)
	)
	(wire
		(pts
			(xy 146.05 129.54) (xy 148.59 129.54)
		)
		(stroke
			(width 0)
			(type default)
		)
	)
	(wire
		(pts
			(xy 161.29 160.02) (xy 170.18 160.02)
		)
		(stroke
			(width 0)
			(type default)
		)
	)
	(wire
		(pts
			(xy 208.28 90.17) (xy 229.87 90.17)
		)
		(stroke
			(width 0)
			(type default)
		)
	)
	(wire
		(pts
			(xy 187.96 144.78) (xy 199.39 144.78)
		)
		(stroke
			(width 0)
			(type default)
		)
	)
	(wire
		(pts
			(xy 158.75 127) (xy 158.75 129.54)
		)
		(stroke
			(width 0)
			(type default)
		)
	)
	(wire
		(pts
			(xy 184.15 247.65) (xy 184.15 245.11)
		)
		(stroke
			(width 0)
			(type default)
		)
	)
	(bus
		(pts
			(xy 132.08 55.88) (xy 130.81 54.61)
		)
		(stroke
			(width 0)
			(type default)
		)
	)
	(wire
		(pts
			(xy 245.11 219.71) (xy 245.11 222.25)
		)
		(stroke
			(width 0)
			(type default)
		)
	)
	(wire
		(pts
			(xy 179.07 219.71) (xy 177.8 219.71)
		)
		(stroke
			(width 0)
			(type default)
		)
	)
	(wire
		(pts
			(xy 242.57 234.95) (xy 242.57 227.33)
		)
		(stroke
			(width 0)
			(type default)
		)
	)
	(wire
		(pts
			(xy 149.86 22.86) (xy 149.86 25.4)
		)
		(stroke
			(width 0)
			(type default)
		)
	)
	(wire
		(pts
			(xy 234.95 69.85) (xy 257.81 69.85)
		)
		(stroke
			(width 0)
			(type default)
		)
	)
	(wire
		(pts
			(xy 140.97 22.86) (xy 149.86 22.86)
		)
		(stroke
			(width 0)
			(type default)
		)
	)
	(wire
		(pts
			(xy 237.49 74.93) (xy 257.81 74.93)
		)
		(stroke
			(width 0)
			(type default)
		)
	)
	(wire
		(pts
			(xy 167.64 22.86) (xy 179.07 22.86)
		)
		(stroke
			(width 0)
			(type default)
		)
	)
	(wire
		(pts
			(xy 209.55 118.11) (xy 209.55 115.57)
		)
		(stroke
			(width 0)
			(type default)
		)
	)
	(wire
		(pts
			(xy 151.13 95.25) (xy 151.13 97.79)
		)
		(stroke
			(width 0)
			(type default)
		)
	)
	(wire
		(pts
			(xy 199.39 160.02) (xy 214.63 160.02)
		)
		(stroke
			(width 0)
			(type default)
		)
	)
	(wire
		(pts
			(xy 167.64 38.1) (xy 179.07 38.1)
		)
		(stroke
			(width 0)
			(type default)
		)
	)
	(wire
		(pts
			(xy 179.07 38.1) (xy 179.07 54.61)
		)
		(stroke
			(width 0)
			(type default)
		)
	)
	(wire
		(pts
			(xy 234.95 219.71) (xy 237.49 219.71)
		)
		(stroke
			(width 0)
			(type default)
		)
	)
	(wire
		(pts
			(xy 167.64 22.86) (xy 167.64 25.4)
		)
		(stroke
			(width 0)
			(type default)
		)
	)
	(wire
		(pts
			(xy 185.42 107.95) (xy 148.59 107.95)
		)
		(stroke
			(width 0)
			(type default)
		)
	)
	(wire
		(pts
			(xy 234.95 245.11) (xy 234.95 246.38)
		)
		(stroke
			(width 0)
			(type default)
		)
	)
	(wire
		(pts
			(xy 208.28 113.03) (xy 209.55 113.03)
		)
		(stroke
			(width 0)
			(type default)
		)
	)
	(bus
		(pts
			(xy 132.08 66.04) (xy 132.08 68.58)
		)
		(stroke
			(width 0)
			(type default)
		)
	)
	(wire
		(pts
			(xy 234.95 77.47) (xy 257.81 77.47)
		)
		(stroke
			(width 0)
			(type default)
		)
	)
	(wire
		(pts
			(xy 208.28 82.55) (xy 232.41 82.55)
		)
		(stroke
			(width 0)
			(type default)
		)
	)
	(bus
		(pts
			(xy 259.08 58.42) (xy 259.08 60.96)
		)
		(stroke
			(width 0)
			(type default)
		)
	)
	(wire
		(pts
			(xy 237.49 242.57) (xy 237.49 246.38)
		)
		(stroke
			(width 0)
			(type default)
		)
	)
	(bus
		(pts
			(xy 259.08 205.74) (xy 259.08 208.28)
		)
		(stroke
			(width 0)
			(type default)
		)
	)
	(wire
		(pts
			(xy 170.18 160.02) (xy 179.07 160.02)
		)
		(stroke
			(width 0)
			(type default)
		)
	)
	(wire
		(pts
			(xy 133.35 207.01) (xy 154.94 207.01)
		)
		(stroke
			(width 0)
			(type default)
		)
	)
	(wire
		(pts
			(xy 208.28 232.41) (xy 245.11 232.41)
		)
		(stroke
			(width 0)
			(type default)
		)
	)
	(wire
		(pts
			(xy 151.13 110.49) (xy 151.13 102.87)
		)
		(stroke
			(width 0)
			(type default)
		)
	)
	(wire
		(pts
			(xy 156.21 102.87) (xy 156.21 118.11)
		)
		(stroke
			(width 0)
			(type default)
		)
	)
	(bus
		(pts
			(xy 132.08 81.28) (xy 132.08 83.82)
		)
		(stroke
			(width 0)
			(type default)
		)
	)
	(wire
		(pts
			(xy 133.35 74.93) (xy 185.42 74.93)
		)
		(stroke
			(width 0)
			(type default)
		)
	)
	(wire
		(pts
			(xy 208.28 240.03) (xy 240.03 240.03)
		)
		(stroke
			(width 0)
			(type default)
		)
	)
	(bus
		(pts
			(xy 132.08 58.42) (xy 132.08 60.96)
		)
		(stroke
			(width 0)
			(type default)
		)
	)
	(wire
		(pts
			(xy 245.11 219.71) (xy 247.65 219.71)
		)
		(stroke
			(width 0)
			(type default)
		)
	)
	(wire
		(pts
			(xy 153.67 95.25) (xy 153.67 97.79)
		)
		(stroke
			(width 0)
			(type default)
		)
	)
	(wire
		(pts
			(xy 133.35 186.69) (xy 152.4 186.69)
		)
		(stroke
			(width 0)
			(type default)
		)
	)
	(wire
		(pts
			(xy 133.35 201.93) (xy 152.4 201.93)
		)
		(stroke
			(width 0)
			(type default)
		)
	)
	(wire
		(pts
			(xy 181.61 175.26) (xy 250.19 175.26)
		)
		(stroke
			(width 0)
			(type default)
		)
	)
	(wire
		(pts
			(xy 234.95 62.23) (xy 257.81 62.23)
		)
		(stroke
			(width 0)
			(type default)
		)
	)
	(wire
		(pts
			(xy 208.28 85.09) (xy 229.87 85.09)
		)
		(stroke
			(width 0)
			(type default)
		)
	)
	(wire
		(pts
			(xy 208.28 62.23) (xy 229.87 62.23)
		)
		(stroke
			(width 0)
			(type default)
		)
	)
	(wire
		(pts
			(xy 156.21 118.11) (xy 185.42 118.11)
		)
		(stroke
			(width 0)
			(type default)
		)
	)
	(wire
		(pts
			(xy 250.19 175.26) (xy 250.19 90.17)
		)
		(stroke
			(width 0)
			(type default)
		)
	)
	(label "RX_EQ0"
		(at 226.06 229.87 180)
		(effects
			(font
				(size 1.27 1.27)
			)
			(justify right bottom)
		)
	)
	(label "PCIe_{I}.RX0-"
		(at 135.89 209.55 0)
		(effects
			(font
				(size 1.27 1.27)
			)
			(justify left bottom)
		)
	)
	(label "PCIe_{O}_C.TX1-"
		(at 224.79 74.93 180)
		(effects
			(font
				(size 1.27 1.27)
			)
			(justify right bottom)
		)
	)
	(label "PCIe_{I}.TX3+"
		(at 135.89 62.23 0)
		(effects
			(font
				(size 1.27 1.27)
			)
			(justify left bottom)
		)
	)
	(label "PCIe_{O}.RX0+"
		(at 250.19 207.01 180)
		(effects
			(font
				(size 1.27 1.27)
			)
			(justify right bottom)
		)
	)
	(label "PCIe_{O}_C.TX0+"
		(at 224.79 85.09 180)
		(effects
			(font
				(size 1.27 1.27)
			)
			(justify right bottom)
		)
	)
	(label "PCIe_{O}.RX2+"
		(at 250.19 191.77 180)
		(effects
			(font
				(size 1.27 1.27)
			)
			(justify right bottom)
		)
	)
	(label "PCIe_{O}.TX1-"
		(at 254 74.93 180)
		(effects
			(font
				(size 1.27 1.27)
			)
			(justify right bottom)
		)
	)
	(label "PCIe_{I}.TX2+"
		(at 135.89 69.85 0)
		(effects
			(font
				(size 1.27 1.27)
			)
			(justify left bottom)
		)
	)
	(label "TX_FG0"
		(at 167.64 115.57 0)
		(effects
			(font
				(size 1.27 1.27)
			)
			(justify left bottom)
		)
	)
	(label "PCIe_{I}_C.RX1+"
		(at 166.37 199.39 0)
		(effects
			(font
				(size 1.27 1.27)
			)
			(justify left bottom)
		)
	)
	(label "PCIe_{I}_C.RX3+"
		(at 166.37 184.15 0)
		(effects
			(font
				(size 1.27 1.27)
			)
			(justify left bottom)
		)
	)
	(label "PCIe_{O}.TX0+"
		(at 254 85.09 180)
		(effects
			(font
				(size 1.27 1.27)
			)
			(justify right bottom)
		)
	)
	(label "PCIe_{I}.TX0+"
		(at 135.89 85.09 0)
		(effects
			(font
				(size 1.27 1.27)
			)
			(justify left bottom)
		)
	)
	(label "PCIe_{O}.TX3-"
		(at 254 59.69 180)
		(effects
			(font
				(size 1.27 1.27)
			)
			(justify right bottom)
		)
	)
	(label "RX_FG1"
		(at 226.06 242.57 180)
		(effects
			(font
				(size 1.27 1.27)
			)
			(justify right bottom)
		)
	)
	(label "PCIe_{I}_C.RX2+"
		(at 166.37 191.77 0)
		(effects
			(font
				(size 1.27 1.27)
			)
			(justify left bottom)
		)
	)
	(label "PCIe_{O}_C.TX1+"
		(at 224.79 77.47 180)
		(effects
			(font
				(size 1.27 1.27)
			)
			(justify right bottom)
		)
	)
	(label "PCIe_{I}_C.RX0+"
		(at 166.37 207.01 0)
		(effects
			(font
				(size 1.27 1.27)
			)
			(justify left bottom)
		)
	)
	(label "PCIe_{I}.RX2+"
		(at 135.89 191.77 0)
		(effects
			(font
				(size 1.27 1.27)
			)
			(justify left bottom)
		)
	)
	(label "PCIe_{I}.RX3+"
		(at 135.89 184.15 0)
		(effects
			(font
				(size 1.27 1.27)
			)
			(justify left bottom)
		)
	)
	(label "PCIe_{O}.TX1+"
		(at 254 77.47 180)
		(effects
			(font
				(size 1.27 1.27)
			)
			(justify right bottom)
		)
	)
	(label "PCIe_{I}_C.RX0-"
		(at 166.37 209.55 0)
		(effects
			(font
				(size 1.27 1.27)
			)
			(justify left bottom)
		)
	)
	(label "PCIe_{I}_C.RX3-"
		(at 166.37 186.69 0)
		(effects
			(font
				(size 1.27 1.27)
			)
			(justify left bottom)
		)
	)
	(label "PCIe_{I}_C.RX2-"
		(at 166.37 194.31 0)
		(effects
			(font
				(size 1.27 1.27)
			)
			(justify left bottom)
		)
	)
	(label "RX_FG0"
		(at 226.06 240.03 180)
		(effects
			(font
				(size 1.27 1.27)
			)
			(justify right bottom)
		)
	)
	(label "PCIe_{O}_C.TX2-"
		(at 224.79 67.31 180)
		(effects
			(font
				(size 1.27 1.27)
			)
			(justify right bottom)
		)
	)
	(label "TX_FG1"
		(at 167.64 118.11 0)
		(effects
			(font
				(size 1.27 1.27)
			)
			(justify left bottom)
		)
	)
	(label "PCIe_{O}.TX3+"
		(at 254 62.23 180)
		(effects
			(font
				(size 1.27 1.27)
			)
			(justify right bottom)
		)
	)
	(label "RX_EQ2"
		(at 226.06 234.95 180)
		(effects
			(font
				(size 1.27 1.27)
			)
			(justify right bottom)
		)
	)
	(label "TX_SW"
		(at 167.64 120.65 0)
		(effects
			(font
				(size 1.27 1.27)
			)
			(justify left bottom)
		)
	)
	(label "PCIe_{I}.RX1-"
		(at 135.89 201.93 0)
		(effects
			(font
				(size 1.27 1.27)
			)
			(justify left bottom)
		)
	)
	(label "PCIe_{I}.TX0-"
		(at 135.89 82.55 0)
		(effects
			(font
				(size 1.27 1.27)
			)
			(justify left bottom)
		)
	)
	(label "PCIe_{O}.RX0-"
		(at 250.19 209.55 180)
		(effects
			(font
				(size 1.27 1.27)
			)
			(justify right bottom)
		)
	)
	(label "PCIe_{O}.RX1-"
		(at 250.19 201.93 180)
		(effects
			(font
				(size 1.27 1.27)
			)
			(justify right bottom)
		)
	)
	(label "PCIe_{O}.RX2-"
		(at 250.19 194.31 180)
		(effects
			(font
				(size 1.27 1.27)
			)
			(justify right bottom)
		)
	)
	(label "TX_EQ0"
		(at 167.64 105.41 0)
		(effects
			(font
				(size 1.27 1.27)
			)
			(justify left bottom)
		)
	)
	(label "PCIe_{O}.TX2+"
		(at 254 69.85 180)
		(effects
			(font
				(size 1.27 1.27)
			)
			(justify right bottom)
		)
	)
	(label "TX_EQ1"
		(at 167.64 107.95 0)
		(effects
			(font
				(size 1.27 1.27)
			)
			(justify left bottom)
		)
	)
	(label "PCIe_{O}.RX1+"
		(at 250.19 199.39 180)
		(effects
			(font
				(size 1.27 1.27)
			)
			(justify right bottom)
		)
	)
	(label "PCIe_{I}.RX3-"
		(at 135.89 186.69 0)
		(effects
			(font
				(size 1.27 1.27)
			)
			(justify left bottom)
		)
	)
	(label "PCIe_{O}_C.TX2+"
		(at 224.79 69.85 180)
		(effects
			(font
				(size 1.27 1.27)
			)
			(justify right bottom)
		)
	)
	(label "PCIe_{O}_C.TX3-"
		(at 224.79 59.69 180)
		(effects
			(font
				(size 1.27 1.27)
			)
			(justify right bottom)
		)
	)
	(label "RX_EQ1"
		(at 226.06 232.41 180)
		(effects
			(font
				(size 1.27 1.27)
			)
			(justify right bottom)
		)
	)
	(label "PCIe_{I}.RX1+"
		(at 135.89 199.39 0)
		(effects
			(font
				(size 1.27 1.27)
			)
			(justify left bottom)
		)
	)
	(label "PCIe_{I}_C.RX1-"
		(at 166.37 201.93 0)
		(effects
			(font
				(size 1.27 1.27)
			)
			(justify left bottom)
		)
	)
	(label "PCIe_{I}.RX0+"
		(at 135.89 207.01 0)
		(effects
			(font
				(size 1.27 1.27)
			)
			(justify left bottom)
		)
	)
	(label "RX_SW"
		(at 226.06 245.11 180)
		(effects
			(font
				(size 1.27 1.27)
			)
			(justify right bottom)
		)
	)
	(label "PCIe_{O}.TX2-"
		(at 254 67.31 180)
		(effects
			(font
				(size 1.27 1.27)
			)
			(justify right bottom)
		)
	)
	(label "PCIe_{O}.RX3+"
		(at 250.19 184.15 180)
		(effects
			(font
				(size 1.27 1.27)
			)
			(justify right bottom)
		)
	)
	(label "PCIe_{I}.TX1-"
		(at 135.89 74.93 0)
		(effects
			(font
				(size 1.27 1.27)
			)
			(justify left bottom)
		)
	)
	(label "PCIe_{O}.TX0-"
		(at 254 82.55 180)
		(effects
			(font
				(size 1.27 1.27)
			)
			(justify right bottom)
		)
	)
	(label "PCIe_{I}.TX3-"
		(at 135.89 59.69 0)
		(effects
			(font
				(size 1.27 1.27)
			)
			(justify left bottom)
		)
	)
	(label "PCIe_{O}_C.TX0-"
		(at 224.79 82.55 180)
		(effects
			(font
				(size 1.27 1.27)
			)
			(justify right bottom)
		)
	)
	(label "PCIe_{I}.RX2-"
		(at 135.89 194.31 0)
		(effects
			(font
				(size 1.27 1.27)
			)
			(justify left bottom)
		)
	)
	(label "TX_EQ2"
		(at 167.64 110.49 0)
		(effects
			(font
				(size 1.27 1.27)
			)
			(justify left bottom)
		)
	)
	(label "PCIe_{O}.RX3-"
		(at 250.19 186.69 180)
		(effects
			(font
				(size 1.27 1.27)
			)
			(justify right bottom)
		)
	)
	(label "PCIe_{I}.TX2-"
		(at 135.89 67.31 0)
		(effects
			(font
				(size 1.27 1.27)
			)
			(justify left bottom)
		)
	)
	(label "PCIe_{I}.TX1+"
		(at 135.89 77.47 0)
		(effects
			(font
				(size 1.27 1.27)
			)
			(justify left bottom)
		)
	)
	(label "PCIe_{O}_C.TX3+"
		(at 224.79 62.23 180)
		(effects
			(font
				(size 1.27 1.27)
			)
			(justify right bottom)
		)
	)
	(hierarchical_label "~{PRSNT}"
		(shape input)
		(at 266.7 90.17 0)
		(effects
			(font
				(size 1.27 1.27)
			)
			(justify left)
		)
	)
	(hierarchical_label "PCIe_{I}{PCIe}"
		(shape input)
		(at 124.46 54.61 180)
		(effects
			(font
				(size 1.27 1.27)
			)
			(justify right)
		)
	)
	(hierarchical_label "PCIe_{O}{PCIe}"
		(shape output)
		(at 266.7 54.61 0)
		(effects
			(font
				(size 1.27 1.27)
			)
			(justify left)
		)
	)
	(symbol
		(lib_id "antmicropower:GND")
		(at 158.75 30.48 0)
		(unit 1)
		(exclude_from_sim no)
		(in_bom yes)
		(on_board yes)
		(dnp no)
		(property "Reference" "#PWR0301"
			(at 167.64 33.02 0)
			(effects
				(font
					(size 1.27 1.27)
					(thickness 0.15)
				)
				(justify left bottom)
				(hide yes)
			)
		)
		(property "Value" "GND"
			(at 158.75 34.29 0)
			(effects
				(font
					(size 1.27 1.27)
					(thickness 0.15)
				)
			)
		)
		(property "Footprint" ""
			(at 167.64 38.1 0)
			(effects
				(font
					(size 1.27 1.27)
					(thickness 0.15)
				)
				(justify left bottom)
				(hide yes)
			)
		)
		(property "Datasheet" ""
			(at 167.64 43.18 0)
			(effects
				(font
					(size 1.27 1.27)
					(thickness 0.15)
				)
				(justify left bottom)
				(hide yes)
			)
		)
		(property "Description" ""
			(at 158.75 30.48 0)
			(effects
				(font
					(size 1.27 1.27)
				)
				(hide yes)
			)
		)
		(property "Author" "Antmicro"
			(at 167.64 38.1 0)
			(effects
				(font
					(size 1.27 1.27)
					(thickness 0.15)
				)
				(justify left bottom)
				(hide yes)
			)
		)
		(property "License" "Apache-2.0"
			(at 167.64 40.64 0)
			(effects
				(font
					(size 1.27 1.27)
					(thickness 0.15)
				)
				(justify left bottom)
				(hide yes)
			)
		)
		(pin "1"
		)
		(instances
			(project "com-express-7-baseboard"
				(path ""
					(reference "#PWR0301")
					(unit 1)
				)
			)
		)
	)
	(symbol
		(lib_id "antmicroResistors0402:R_1k_0402")
		(at 148.59 127 90)
		(unit 1)
		(exclude_from_sim no)
		(in_bom yes)
		(on_board yes)
		(dnp no)
		(property "Reference" "R205"
			(at 148.59 130.81 0)
			(effects
				(font
					(size 1.27 1.27)
					(thickness 0.15)
				)
				(justify right)
			)
		)
		(property "Value" "R_1k_0402"
			(at 161.29 106.68 0)
			(effects
				(font
					(size 1.27 1.27)
					(thickness 0.15)
				)
				(justify left bottom)
				(hide yes)
			)
		)
		(property "Footprint" "antmicro-footprints:R_0402_1005Metric"
			(at 163.83 106.68 0)
			(effects
				(font
					(size 1.27 1.27)
					(thickness 0.15)
				)
				(justify left bottom)
				(hide yes)
			)
		)
		(property "Datasheet" "https://www.bourns.com/docs/product-datasheets/cr.pdf"
			(at 166.37 106.68 0)
			(effects
				(font
					(size 1.27 1.27)
					(thickness 0.15)
				)
				(justify left bottom)
				(hide yes)
			)
		)
		(property "Description" ""
			(at 148.59 127 0)
			(effects
				(font
					(size 1.27 1.27)
				)
				(hide yes)
			)
		)
		(property "MPN" "CR0402-FX-1001GLF"
			(at 168.91 106.68 0)
			(effects
				(font
					(size 1.27 1.27)
					(thickness 0.15)
				)
				(justify left bottom)
				(hide yes)
			)
		)
		(property "Manufacturer" "Bourns"
			(at 171.45 106.68 0)
			(effects
				(font
					(size 1.27 1.27)
					(thickness 0.15)
				)
				(justify left bottom)
				(hide yes)
			)
		)
		(property "License" "Apache-2.0"
			(at 173.99 106.68 0)
			(effects
				(font
					(size 1.27 1.27)
					(thickness 0.15)
				)
				(justify left bottom)
				(hide yes)
			)
		)
		(property "Author" "Antmicro"
			(at 176.53 106.68 0)
			(effects
				(font
					(size 1.27 1.27)
					(thickness 0.15)
				)
				(justify left bottom)
				(hide yes)
			)
		)
		(property "Val" "1k"
			(at 147.32 127 0)
			(effects
				(font
					(size 1.27 1.27)
					(thickness 0.15)
				)
				(justify right)
			)
		)
		(property "Tolerance" "1%"
			(at 158.75 106.68 0)
			(effects
				(font
					(size 1.27 1.27)
				)
				(justify left bottom)
				(hide yes)
			)
		)
		(property "Public" "False"
			(at 179.07 106.68 0)
			(effects
				(font
					(size 1.27 1.27)
				)
				(justify left bottom)
				(hide yes)
			)
		)
		(pin "1"
		)
		(pin "2"
		)
		(instances
			(project "com-express-7-baseboard"
				(path ""
					(reference "R205")
					(unit 1)
				)
			)
		)
	)
	(symbol
		(lib_id "antmicroCapacitors0402:C_100n_0402")
		(at 179.07 167.64 90)
		(unit 1)
		(exclude_from_sim no)
		(in_bom yes)
		(on_board yes)
		(dnp no)
		(fields_autoplaced yes)
		(property "Reference" "C136"
			(at 181.61 163.8236 90)
			(effects
				(font
					(size 1.27 1.27)
					(thickness 0.15)
				)
				(justify right)
			)
		)
		(property "Value" "C_100n_0402"
			(at 189.23 147.32 0)
			(effects
				(font
					(size 1.27 1.27)
					(thickness 0.15)
				)
				(justify left bottom)
				(hide yes)
			)
		)
		(property "Footprint" "antmicro-footprints:C_0402_1005Metric"
			(at 191.77 147.32 0)
			(effects
				(font
					(size 1.27 1.27)
					(thickness 0.15)
				)
				(justify left bottom)
				(hide yes)
			)
		)
		(property "Datasheet" "https://www.murata.com/products/productdetail?partno=GRM155R61H104KE14%23"
			(at 194.31 147.32 0)
			(effects
				(font
					(size 1.27 1.27)
					(thickness 0.15)
				)
				(justify left bottom)
				(hide yes)
			)
		)
		(property "Description" ""
			(at 179.07 167.64 0)
			(effects
				(font
					(size 1.27 1.27)
				)
				(hide yes)
			)
		)
		(property "MPN" "GRM155R61H104KE14D"
			(at 196.85 147.32 0)
			(effects
				(font
					(size 1.27 1.27)
					(thickness 0.15)
				)
				(justify left bottom)
				(hide yes)
			)
		)
		(property "Manufacturer" "Murata"
			(at 199.39 147.32 0)
			(effects
				(font
					(size 1.27 1.27)
					(thickness 0.15)
				)
				(justify left bottom)
				(hide yes)
			)
		)
		(property "License" "Apache-2.0"
			(at 201.93 147.32 0)
			(effects
				(font
					(size 1.27 1.27)
					(thickness 0.15)
				)
				(justify left bottom)
				(hide yes)
			)
		)
		(property "Author" "Antmicro"
			(at 204.47 147.32 0)
			(effects
				(font
					(size 1.27 1.27)
					(thickness 0.15)
				)
				(justify left bottom)
				(hide yes)
			)
		)
		(property "Val" "100n"
			(at 181.61 166.3636 90)
			(effects
				(font
					(size 1.27 1.27)
					(thickness 0.15)
				)
				(justify right)
			)
		)
		(property "Voltage" "50V"
			(at 207.01 147.32 0)
			(effects
				(font
					(size 1.27 1.27)
				)
				(justify left bottom)
				(hide yes)
			)
		)
		(property "Dielectric" "X5R"
			(at 209.55 147.32 0)
			(effects
				(font
					(size 1.27 1.27)
				)
				(justify left bottom)
				(hide yes)
			)
		)
		(property "Public" "False"
			(at 212.09 147.32 0)
			(effects
				(font
					(size 1.27 1.27)
				)
				(justify left bottom)
				(hide yes)
			)
		)
		(pin "1"
		)
		(pin "2"
		)
		(instances
			(project "com-express-7-baseboard"
				(path ""
					(reference "C136")
					(unit 1)
				)
			)
		)
	)
	(symbol
		(lib_id "antmicroCapacitors0402:C_220n_0402")
		(at 229.87 77.47 0)
		(unit 1)
		(exclude_from_sim no)
		(in_bom yes)
		(on_board yes)
		(dnp no)
		(property "Reference" "C141"
			(at 228.6 78.74 0)
			(effects
				(font
					(size 1.27 1.27)
					(thickness 0.15)
				)
			)
		)
		(property "Value" "C_220n_0402"
			(at 250.19 87.63 0)
			(effects
				(font
					(size 1.27 1.27)
					(thickness 0.15)
				)
				(justify left bottom)
				(hide yes)
			)
		)
		(property "Footprint" "antmicro-footprints:C_0402_1005Metric"
			(at 250.19 90.17 0)
			(effects
				(font
					(size 1.27 1.27)
					(thickness 0.15)
				)
				(justify left bottom)
				(hide yes)
			)
		)
		(property "Datasheet" "https://www.yageo.com/en/Chart/Download/pdf/CC0402KRX5R6BB224"
			(at 250.19 92.71 0)
			(effects
				(font
					(size 1.27 1.27)
					(thickness 0.15)
				)
				(justify left bottom)
				(hide yes)
			)
		)
		(property "Description" ""
			(at 229.87 77.47 0)
			(effects
				(font
					(size 1.27 1.27)
				)
				(hide yes)
			)
		)
		(property "MPN" "CC0402KRX5R6BB224"
			(at 250.19 95.25 0)
			(effects
				(font
					(size 1.27 1.27)
					(thickness 0.15)
				)
				(justify left bottom)
				(hide yes)
			)
		)
		(property "Manufacturer" "YAGEO"
			(at 250.19 97.79 0)
			(effects
				(font
					(size 1.27 1.27)
					(thickness 0.15)
				)
				(justify left bottom)
				(hide yes)
			)
		)
		(property "License" "Apache-2.0"
			(at 250.19 100.33 0)
			(effects
				(font
					(size 1.27 1.27)
					(thickness 0.15)
				)
				(justify left bottom)
				(hide yes)
			)
		)
		(property "Author" "Antmicro"
			(at 250.19 102.87 0)
			(effects
				(font
					(size 1.27 1.27)
					(thickness 0.15)
				)
				(justify left bottom)
				(hide yes)
			)
		)
		(property "Val" "220n"
			(at 236.22 78.74 0)
			(effects
				(font
					(size 1.27 1.27)
					(thickness 0.15)
				)
			)
		)
		(property "Voltage" ""
			(at 250.19 105.41 0)
			(effects
				(font
					(size 1.27 1.27)
				)
				(justify left bottom)
				(hide yes)
			)
		)
		(property "Dielectric" ""
			(at 250.19 107.95 0)
			(effects
				(font
					(size 1.27 1.27)
				)
				(justify left bottom)
				(hide yes)
			)
		)
		(property "Public" "False"
			(at 250.19 110.49 0)
			(effects
				(font
					(size 1.27 1.27)
				)
				(justify left bottom)
				(hide yes)
			)
		)
		(pin "1"
		)
		(pin "2"
		)
		(instances
			(project "com-express-7-baseboard"
				(path ""
					(reference "C141")
					(unit 1)
				)
			)
		)
	)
	(symbol
		(lib_id "antmicroCapacitors0402:C_220n_0402")
		(at 232.41 67.31 0)
		(unit 1)
		(exclude_from_sim no)
		(in_bom yes)
		(on_board yes)
		(dnp no)
		(property "Reference" "C144"
			(at 231.14 66.04 0)
			(effects
				(font
					(size 1.27 1.27)
					(thickness 0.15)
				)
			)
		)
		(property "Value" "C_220n_0402"
			(at 252.73 77.47 0)
			(effects
				(font
					(size 1.27 1.27)
					(thickness 0.15)
				)
				(justify left bottom)
				(hide yes)
			)
		)
		(property "Footprint" "antmicro-footprints:C_0402_1005Metric"
			(at 252.73 80.01 0)
			(effects
				(font
					(size 1.27 1.27)
					(thickness 0.15)
				)
				(justify left bottom)
				(hide yes)
			)
		)
		(property "Datasheet" "https://www.yageo.com/en/Chart/Download/pdf/CC0402KRX5R6BB224"
			(at 252.73 82.55 0)
			(effects
				(font
					(size 1.27 1.27)
					(thickness 0.15)
				)
				(justify left bottom)
				(hide yes)
			)
		)
		(property "Description" ""
			(at 232.41 67.31 0)
			(effects
				(font
					(size 1.27 1.27)
				)
				(hide yes)
			)
		)
		(property "MPN" "CC0402KRX5R6BB224"
			(at 252.73 85.09 0)
			(effects
				(font
					(size 1.27 1.27)
					(thickness 0.15)
				)
				(justify left bottom)
				(hide yes)
			)
		)
		(property "Manufacturer" "YAGEO"
			(at 252.73 87.63 0)
			(effects
				(font
					(size 1.27 1.27)
					(thickness 0.15)
				)
				(justify left bottom)
				(hide yes)
			)
		)
		(property "License" "Apache-2.0"
			(at 252.73 90.17 0)
			(effects
				(font
					(size 1.27 1.27)
					(thickness 0.15)
				)
				(justify left bottom)
				(hide yes)
			)
		)
		(property "Author" "Antmicro"
			(at 252.73 92.71 0)
			(effects
				(font
					(size 1.27 1.27)
					(thickness 0.15)
				)
				(justify left bottom)
				(hide yes)
			)
		)
		(property "Val" "220n"
			(at 238.76 66.04 0)
			(effects
				(font
					(size 1.27 1.27)
					(thickness 0.15)
				)
			)
		)
		(property "Voltage" ""
			(at 252.73 95.25 0)
			(effects
				(font
					(size 1.27 1.27)
				)
				(justify left bottom)
				(hide yes)
			)
		)
		(property "Dielectric" ""
			(at 252.73 97.79 0)
			(effects
				(font
					(size 1.27 1.27)
				)
				(justify left bottom)
				(hide yes)
			)
		)
		(property "Public" "False"
			(at 252.73 100.33 0)
			(effects
				(font
					(size 1.27 1.27)
				)
				(justify left bottom)
				(hide yes)
			)
		)
		(pin "1"
		)
		(pin "2"
		)
		(instances
			(project "com-express-7-baseboard"
				(path ""
					(reference "C144")
					(unit 1)
				)
			)
		)
	)
	(symbol
		(lib_id "antmicroCapacitors0402:C_100n_0402")
		(at 132.08 45.72 90)
		(unit 1)
		(exclude_from_sim no)
		(in_bom yes)
		(on_board yes)
		(dnp no)
		(fields_autoplaced yes)
		(property "Reference" "C112"
			(at 134.62 41.9036 90)
			(effects
				(font
					(size 1.27 1.27)
					(thickness 0.15)
				)
				(justify right)
			)
		)
		(property "Value" "C_100n_0402"
			(at 142.24 25.4 0)
			(effects
				(font
					(size 1.27 1.27)
					(thickness 0.15)
				)
				(justify left bottom)
				(hide yes)
			)
		)
		(property "Footprint" "antmicro-footprints:C_0402_1005Metric"
			(at 144.78 25.4 0)
			(effects
				(font
					(size 1.27 1.27)
					(thickness 0.15)
				)
				(justify left bottom)
				(hide yes)
			)
		)
		(property "Datasheet" "https://www.murata.com/products/productdetail?partno=GRM155R61H104KE14%23"
			(at 147.32 25.4 0)
			(effects
				(font
					(size 1.27 1.27)
					(thickness 0.15)
				)
				(justify left bottom)
				(hide yes)
			)
		)
		(property "Description" ""
			(at 132.08 45.72 0)
			(effects
				(font
					(size 1.27 1.27)
				)
				(hide yes)
			)
		)
		(property "MPN" "GRM155R61H104KE14D"
			(at 149.86 25.4 0)
			(effects
				(font
					(size 1.27 1.27)
					(thickness 0.15)
				)
				(justify left bottom)
				(hide yes)
			)
		)
		(property "Manufacturer" "Murata"
			(at 152.4 25.4 0)
			(effects
				(font
					(size 1.27 1.27)
					(thickness 0.15)
				)
				(justify left bottom)
				(hide yes)
			)
		)
		(property "License" "Apache-2.0"
			(at 154.94 25.4 0)
			(effects
				(font
					(size 1.27 1.27)
					(thickness 0.15)
				)
				(justify left bottom)
				(hide yes)
			)
		)
		(property "Author" "Antmicro"
			(at 157.48 25.4 0)
			(effects
				(font
					(size 1.27 1.27)
					(thickness 0.15)
				)
				(justify left bottom)
				(hide yes)
			)
		)
		(property "Val" "100n"
			(at 134.62 44.4436 90)
			(effects
				(font
					(size 1.27 1.27)
					(thickness 0.15)
				)
				(justify right)
			)
		)
		(property "Voltage" "50V"
			(at 160.02 25.4 0)
			(effects
				(font
					(size 1.27 1.27)
				)
				(justify left bottom)
				(hide yes)
			)
		)
		(property "Dielectric" "X5R"
			(at 162.56 25.4 0)
			(effects
				(font
					(size 1.27 1.27)
				)
				(justify left bottom)
				(hide yes)
			)
		)
		(property "Public" "False"
			(at 165.1 25.4 0)
			(effects
				(font
					(size 1.27 1.27)
				)
				(justify left bottom)
				(hide yes)
			)
		)
		(pin "1"
		)
		(pin "2"
		)
		(instances
			(project "com-express-7-baseboard"
				(path ""
					(reference "C112")
					(unit 1)
				)
			)
		)
	)
	(symbol
		(lib_id "antmicropower:GND")
		(at 132.08 45.72 0)
		(unit 1)
		(exclude_from_sim no)
		(in_bom yes)
		(on_board yes)
		(dnp no)
		(property "Reference" "#PWR0291"
			(at 140.97 48.26 0)
			(effects
				(font
					(size 1.27 1.27)
					(thickness 0.15)
				)
				(justify left bottom)
				(hide yes)
			)
		)
		(property "Value" "GND"
			(at 132.08 49.53 0)
			(effects
				(font
					(size 1.27 1.27)
					(thickness 0.15)
				)
			)
		)
		(property "Footprint" ""
			(at 140.97 53.34 0)
			(effects
				(font
					(size 1.27 1.27)
					(thickness 0.15)
				)
				(justify left bottom)
				(hide yes)
			)
		)
		(property "Datasheet" ""
			(at 140.97 58.42 0)
			(effects
				(font
					(size 1.27 1.27)
					(thickness 0.15)
				)
				(justify left bottom)
				(hide yes)
			)
		)
		(property "Description" ""
			(at 132.08 45.72 0)
			(effects
				(font
					(size 1.27 1.27)
				)
				(hide yes)
			)
		)
		(property "Author" "Antmicro"
			(at 140.97 53.34 0)
			(effects
				(font
					(size 1.27 1.27)
					(thickness 0.15)
				)
				(justify left bottom)
				(hide yes)
			)
		)
		(property "License" "Apache-2.0"
			(at 140.97 55.88 0)
			(effects
				(font
					(size 1.27 1.27)
					(thickness 0.15)
				)
				(justify left bottom)
				(hide yes)
			)
		)
		(pin "1"
		)
		(instances
			(project "com-express-7-baseboard"
				(path ""
					(reference "#PWR0291")
					(unit 1)
				)
			)
		)
	)
	(symbol
		(lib_id "antmicroCapacitors0402:C_220n_0402")
		(at 232.41 82.55 0)
		(unit 1)
		(exclude_from_sim no)
		(in_bom yes)
		(on_board yes)
		(dnp no)
		(property "Reference" "C146"
			(at 231.14 81.28 0)
			(effects
				(font
					(size 1.27 1.27)
					(thickness 0.15)
				)
			)
		)
		(property "Value" "C_220n_0402"
			(at 252.73 92.71 0)
			(effects
				(font
					(size 1.27 1.27)
					(thickness 0.15)
				)
				(justify left bottom)
				(hide yes)
			)
		)
		(property "Footprint" "antmicro-footprints:C_0402_1005Metric"
			(at 252.73 95.25 0)
			(effects
				(font
					(size 1.27 1.27)
					(thickness 0.15)
				)
				(justify left bottom)
				(hide yes)
			)
		)
		(property "Datasheet" "https://www.yageo.com/en/Chart/Download/pdf/CC0402KRX5R6BB224"
			(at 252.73 97.79 0)
			(effects
				(font
					(size 1.27 1.27)
					(thickness 0.15)
				)
				(justify left bottom)
				(hide yes)
			)
		)
		(property "Description" ""
			(at 232.41 82.55 0)
			(effects
				(font
					(size 1.27 1.27)
				)
				(hide yes)
			)
		)
		(property "MPN" "CC0402KRX5R6BB224"
			(at 252.73 100.33 0)
			(effects
				(font
					(size 1.27 1.27)
					(thickness 0.15)
				)
				(justify left bottom)
				(hide yes)
			)
		)
		(property "Manufacturer" "YAGEO"
			(at 252.73 102.87 0)
			(effects
				(font
					(size 1.27 1.27)
					(thickness 0.15)
				)
				(justify left bottom)
				(hide yes)
			)
		)
		(property "License" "Apache-2.0"
			(at 252.73 105.41 0)
			(effects
				(font
					(size 1.27 1.27)
					(thickness 0.15)
				)
				(justify left bottom)
				(hide yes)
			)
		)
		(property "Author" "Antmicro"
			(at 252.73 107.95 0)
			(effects
				(font
					(size 1.27 1.27)
					(thickness 0.15)
				)
				(justify left bottom)
				(hide yes)
			)
		)
		(property "Val" "220n"
			(at 238.76 81.28 0)
			(effects
				(font
					(size 1.27 1.27)
					(thickness 0.15)
				)
			)
		)
		(property "Voltage" ""
			(at 252.73 110.49 0)
			(effects
				(font
					(size 1.27 1.27)
				)
				(justify left bottom)
				(hide yes)
			)
		)
		(property "Dielectric" ""
			(at 252.73 113.03 0)
			(effects
				(font
					(size 1.27 1.27)
				)
				(justify left bottom)
				(hide yes)
			)
		)
		(property "Public" "False"
			(at 252.73 115.57 0)
			(effects
				(font
					(size 1.27 1.27)
				)
				(justify left bottom)
				(hide yes)
			)
		)
		(pin "1"
		)
		(pin "2"
		)
		(instances
			(project "com-express-7-baseboard"
				(path ""
					(reference "C146")
					(unit 1)
				)
			)
		)
	)
	(symbol
		(lib_id "antmicroCapacitors0402:C_220n_0402")
		(at 229.87 62.23 0)
		(unit 1)
		(exclude_from_sim no)
		(in_bom yes)
		(on_board yes)
		(dnp no)
		(property "Reference" "C139"
			(at 228.6 63.5 0)
			(effects
				(font
					(size 1.27 1.27)
					(thickness 0.15)
				)
			)
		)
		(property "Value" "C_220n_0402"
			(at 250.19 72.39 0)
			(effects
				(font
					(size 1.27 1.27)
					(thickness 0.15)
				)
				(justify left bottom)
				(hide yes)
			)
		)
		(property "Footprint" "antmicro-footprints:C_0402_1005Metric"
			(at 250.19 74.93 0)
			(effects
				(font
					(size 1.27 1.27)
					(thickness 0.15)
				)
				(justify left bottom)
				(hide yes)
			)
		)
		(property "Datasheet" "https://www.yageo.com/en/Chart/Download/pdf/CC0402KRX5R6BB224"
			(at 250.19 77.47 0)
			(effects
				(font
					(size 1.27 1.27)
					(thickness 0.15)
				)
				(justify left bottom)
				(hide yes)
			)
		)
		(property "Description" ""
			(at 229.87 62.23 0)
			(effects
				(font
					(size 1.27 1.27)
				)
				(hide yes)
			)
		)
		(property "MPN" "CC0402KRX5R6BB224"
			(at 250.19 80.01 0)
			(effects
				(font
					(size 1.27 1.27)
					(thickness 0.15)
				)
				(justify left bottom)
				(hide yes)
			)
		)
		(property "Manufacturer" "YAGEO"
			(at 250.19 82.55 0)
			(effects
				(font
					(size 1.27 1.27)
					(thickness 0.15)
				)
				(justify left bottom)
				(hide yes)
			)
		)
		(property "License" "Apache-2.0"
			(at 250.19 85.09 0)
			(effects
				(font
					(size 1.27 1.27)
					(thickness 0.15)
				)
				(justify left bottom)
				(hide yes)
			)
		)
		(property "Author" "Antmicro"
			(at 250.19 87.63 0)
			(effects
				(font
					(size 1.27 1.27)
					(thickness 0.15)
				)
				(justify left bottom)
				(hide yes)
			)
		)
		(property "Val" "220n"
			(at 236.22 63.5 0)
			(effects
				(font
					(size 1.27 1.27)
					(thickness 0.15)
				)
			)
		)
		(property "Voltage" ""
			(at 250.19 90.17 0)
			(effects
				(font
					(size 1.27 1.27)
				)
				(justify left bottom)
				(hide yes)
			)
		)
		(property "Dielectric" ""
			(at 250.19 92.71 0)
			(effects
				(font
					(size 1.27 1.27)
				)
				(justify left bottom)
				(hide yes)
			)
		)
		(property "Public" "False"
			(at 250.19 95.25 0)
			(effects
				(font
					(size 1.27 1.27)
				)
				(justify left bottom)
				(hide yes)
			)
		)
		(pin "1"
		)
		(pin "2"
		)
		(instances
			(project "com-express-7-baseboard"
				(path ""
					(reference "C139")
					(unit 1)
				)
			)
		)
	)
	(symbol
		(lib_id "antmicroResistors0402:R_0R_0402")
		(at 171.45 95.25 180)
		(unit 1)
		(exclude_from_sim no)
		(in_bom yes)
		(on_board yes)
		(dnp no)
		(property "Reference" "R214"
			(at 161.29 93.98 0)
			(effects
				(font
					(size 1.27 1.27)
					(thickness 0.15)
				)
				(justify right)
			)
		)
		(property "Value" "R_0R_0402"
			(at 151.13 82.55 0)
			(effects
				(font
					(size 1.27 1.27)
					(thickness 0.15)
				)
				(justify left bottom)
				(hide yes)
			)
		)
		(property "Footprint" "antmicro-footprints:R_0402_1005Metric"
			(at 151.13 80.01 0)
			(effects
				(font
					(size 1.27 1.27)
					(thickness 0.15)
				)
				(justify left bottom)
				(hide yes)
			)
		)
		(property "Datasheet" "https://industrial.panasonic.com/cdbs/www-data/pdf/RDA0000/AOA0000C301.pdf"
			(at 151.13 77.47 0)
			(effects
				(font
					(size 1.27 1.27)
					(thickness 0.15)
				)
				(justify left bottom)
				(hide yes)
			)
		)
		(property "Description" ""
			(at 171.45 95.25 0)
			(effects
				(font
					(size 1.27 1.27)
				)
				(hide yes)
			)
		)
		(property "MPN" "ERJ2GE0R00X"
			(at 151.13 74.93 0)
			(effects
				(font
					(size 1.27 1.27)
					(thickness 0.15)
				)
				(justify left bottom)
				(hide yes)
			)
		)
		(property "Manufacturer" "Panasonic"
			(at 151.13 72.39 0)
			(effects
				(font
					(size 1.27 1.27)
					(thickness 0.15)
				)
				(justify left bottom)
				(hide yes)
			)
		)
		(property "License" "Apache-2.0"
			(at 151.13 69.85 0)
			(effects
				(font
					(size 1.27 1.27)
					(thickness 0.15)
				)
				(justify left bottom)
				(hide yes)
			)
		)
		(property "Author" "Antmicro"
			(at 151.13 67.31 0)
			(effects
				(font
					(size 1.27 1.27)
					(thickness 0.15)
				)
				(justify left bottom)
				(hide yes)
			)
		)
		(property "Val" "0R"
			(at 171.45 93.98 0)
			(effects
				(font
					(size 1.27 1.27)
					(thickness 0.15)
				)
				(justify right)
			)
		)
		(property "Tolerance" "~"
			(at 151.13 85.09 0)
			(effects
				(font
					(size 1.27 1.27)
				)
				(justify left bottom)
				(hide yes)
			)
		)
		(property "Current" "1A"
			(at 151.13 64.77 0)
			(effects
				(font
					(size 1.27 1.27)
					(thickness 0.15)
				)
				(justify left bottom)
				(hide yes)
			)
		)
		(property "Public" "False"
			(at 151.13 64.77 0)
			(effects
				(font
					(size 1.27 1.27)
				)
				(justify left bottom)
				(hide yes)
			)
		)
		(pin "1"
		)
		(pin "2"
		)
		(instances
			(project "com-express-7-baseboard"
				(path ""
					(reference "R214")
					(unit 1)
				)
			)
		)
	)
	(symbol
		(lib_id "antmicropower:GND")
		(at 143.51 132.08 0)
		(unit 1)
		(exclude_from_sim no)
		(in_bom yes)
		(on_board yes)
		(dnp no)
		(property "Reference" "#PWR0295"
			(at 152.4 134.62 0)
			(effects
				(font
					(size 1.27 1.27)
					(thickness 0.15)
				)
				(justify left bottom)
				(hide yes)
			)
		)
		(property "Value" "GND"
			(at 143.51 135.89 0)
			(effects
				(font
					(size 1.27 1.27)
					(thickness 0.15)
				)
			)
		)
		(property "Footprint" ""
			(at 152.4 139.7 0)
			(effects
				(font
					(size 1.27 1.27)
					(thickness 0.15)
				)
				(justify left bottom)
				(hide yes)
			)
		)
		(property "Datasheet" ""
			(at 152.4 144.78 0)
			(effects
				(font
					(size 1.27 1.27)
					(thickness 0.15)
				)
				(justify left bottom)
				(hide yes)
			)
		)
		(property "Description" ""
			(at 143.51 132.08 0)
			(effects
				(font
					(size 1.27 1.27)
				)
				(hide yes)
			)
		)
		(property "Author" "Antmicro"
			(at 152.4 139.7 0)
			(effects
				(font
					(size 1.27 1.27)
					(thickness 0.15)
				)
				(justify left bottom)
				(hide yes)
			)
		)
		(property "License" "Apache-2.0"
			(at 152.4 142.24 0)
			(effects
				(font
					(size 1.27 1.27)
					(thickness 0.15)
				)
				(justify left bottom)
				(hide yes)
			)
		)
		(pin "1"
		)
		(instances
			(project "com-express-7-baseboard"
				(path ""
					(reference "#PWR0295")
					(unit 1)
				)
			)
		)
	)
	(symbol
		(lib_id "antmicropower:+3V3")
		(at 177.8 218.44 0)
		(mirror y)
		(unit 1)
		(exclude_from_sim no)
		(in_bom yes)
		(on_board yes)
		(dnp no)
		(property "Reference" "#PWR0310"
			(at 162.56 218.44 0)
			(effects
				(font
					(size 1.27 1.27)
					(thickness 0.15)
				)
				(justify left bottom)
				(hide yes)
			)
		)
		(property "Value" "+3V3"
			(at 173.99 217.17 0)
			(effects
				(font
					(size 1.27 1.27)
					(thickness 0.15)
				)
			)
		)
		(property "Footprint" ""
			(at 162.56 226.06 0)
			(effects
				(font
					(size 1.27 1.27)
					(thickness 0.15)
				)
				(justify left bottom)
				(hide yes)
			)
		)
		(property "Datasheet" ""
			(at 162.56 228.6 0)
			(effects
				(font
					(size 1.27 1.27)
					(thickness 0.15)
				)
				(justify left bottom)
				(hide yes)
			)
		)
		(property "Description" ""
			(at 177.8 218.44 0)
			(effects
				(font
					(size 1.27 1.27)
				)
				(hide yes)
			)
		)
		(property "Author" "Antmicro"
			(at 162.56 220.98 0)
			(effects
				(font
					(size 1.27 1.27)
					(thickness 0.15)
				)
				(justify left bottom)
				(hide yes)
			)
		)
		(property "License" "Apache-2.0"
			(at 162.56 223.52 0)
			(effects
				(font
					(size 1.27 1.27)
					(thickness 0.15)
				)
				(justify left bottom)
				(hide yes)
			)
		)
		(pin "1"
		)
		(instances
			(project "com-express-7-baseboard"
				(path ""
					(reference "#PWR0310")
					(unit 1)
				)
			)
		)
	)
	(symbol
		(lib_id "antmicroCapacitors0402:C_100n_0402")
		(at 187.96 167.64 90)
		(unit 1)
		(exclude_from_sim no)
		(in_bom yes)
		(on_board yes)
		(dnp no)
		(fields_autoplaced yes)
		(property "Reference" "C138"
			(at 190.5 163.8236 90)
			(effects
				(font
					(size 1.27 1.27)
					(thickness 0.15)
				)
				(justify right)
			)
		)
		(property "Value" "C_100n_0402"
			(at 198.12 147.32 0)
			(effects
				(font
					(size 1.27 1.27)
					(thickness 0.15)
				)
				(justify left bottom)
				(hide yes)
			)
		)
		(property "Footprint" "antmicro-footprints:C_0402_1005Metric"
			(at 200.66 147.32 0)
			(effects
				(font
					(size 1.27 1.27)
					(thickness 0.15)
				)
				(justify left bottom)
				(hide yes)
			)
		)
		(property "Datasheet" "https://www.murata.com/products/productdetail?partno=GRM155R61H104KE14%23"
			(at 203.2 147.32 0)
			(effects
				(font
					(size 1.27 1.27)
					(thickness 0.15)
				)
				(justify left bottom)
				(hide yes)
			)
		)
		(property "Description" ""
			(at 187.96 167.64 0)
			(effects
				(font
					(size 1.27 1.27)
				)
				(hide yes)
			)
		)
		(property "MPN" "GRM155R61H104KE14D"
			(at 205.74 147.32 0)
			(effects
				(font
					(size 1.27 1.27)
					(thickness 0.15)
				)
				(justify left bottom)
				(hide yes)
			)
		)
		(property "Manufacturer" "Murata"
			(at 208.28 147.32 0)
			(effects
				(font
					(size 1.27 1.27)
					(thickness 0.15)
				)
				(justify left bottom)
				(hide yes)
			)
		)
		(property "License" "Apache-2.0"
			(at 210.82 147.32 0)
			(effects
				(font
					(size 1.27 1.27)
					(thickness 0.15)
				)
				(justify left bottom)
				(hide yes)
			)
		)
		(property "Author" "Antmicro"
			(at 213.36 147.32 0)
			(effects
				(font
					(size 1.27 1.27)
					(thickness 0.15)
				)
				(justify left bottom)
				(hide yes)
			)
		)
		(property "Val" "100n"
			(at 190.5 166.3636 90)
			(effects
				(font
					(size 1.27 1.27)
					(thickness 0.15)
				)
				(justify right)
			)
		)
		(property "Voltage" "50V"
			(at 215.9 147.32 0)
			(effects
				(font
					(size 1.27 1.27)
				)
				(justify left bottom)
				(hide yes)
			)
		)
		(property "Dielectric" "X5R"
			(at 218.44 147.32 0)
			(effects
				(font
					(size 1.27 1.27)
				)
				(justify left bottom)
				(hide yes)
			)
		)
		(property "Public" "False"
			(at 220.98 147.32 0)
			(effects
				(font
					(size 1.27 1.27)
				)
				(justify left bottom)
				(hide yes)
			)
		)
		(pin "1"
		)
		(pin "2"
		)
		(instances
			(project "com-express-7-baseboard"
				(path ""
					(reference "C138")
					(unit 1)
				)
			)
		)
	)
	(symbol
		(lib_id "antmicroTestPoints:TP_0.75mm_SMD")
		(at 210.82 217.17 0)
		(unit 1)
		(exclude_from_sim no)
		(in_bom no)
		(on_board yes)
		(dnp no)
		(property "Reference" "TP54"
			(at 217.17 217.17 0)
			(effects
				(font
					(size 1.27 1.27)
					(thickness 0.15)
				)
			)
		)
		(property "Value" "TP_0.75mm_SMD"
			(at 221.615 220.98 0)
			(effects
				(font
					(size 1.27 1.27)
					(thickness 0.15)
				)
				(justify left bottom)
				(hide yes)
			)
		)
		(property "Footprint" "antmicro-footprints:TP_SMD_0.75mm"
			(at 221.615 223.52 0)
			(effects
				(font
					(size 1.27 1.27)
					(thickness 0.15)
				)
				(justify left bottom)
				(hide yes)
			)
		)
		(property "Datasheet" ""
			(at 228.6 229.87 0)
			(effects
				(font
					(size 1.27 1.27)
					(thickness 0.15)
				)
				(justify left bottom)
				(hide yes)
			)
		)
		(property "Description" ""
			(at 210.82 217.17 0)
			(effects
				(font
					(size 1.27 1.27)
				)
				(hide yes)
			)
		)
		(property "MPN" ""
			(at 221.615 228.6 0)
			(effects
				(font
					(size 1.27 1.27)
					(thickness 0.15)
				)
				(justify left bottom)
				(hide yes)
			)
		)
		(property "Manufacturer" ""
			(at 221.615 223.52 0)
			(effects
				(font
					(size 1.27 1.27)
					(thickness 0.15)
				)
				(justify left bottom)
				(hide yes)
			)
		)
		(property "Author" "Antmicro"
			(at 221.615 226.06 0)
			(effects
				(font
					(size 1.27 1.27)
					(thickness 0.15)
				)
				(justify left bottom)
				(hide yes)
			)
		)
		(property "License" "Apache-2.0"
			(at 221.615 228.6 0)
			(effects
				(font
					(size 1.27 1.27)
					(thickness 0.15)
				)
				(justify left bottom)
				(hide yes)
			)
		)
		(property "Public" "False"
			(at 220.98 231.14 0)
			(effects
				(font
					(size 1.27 1.27)
				)
				(justify left bottom)
				(hide yes)
			)
		)
		(pin "1"
		)
		(instances
			(project "com-express-7-baseboard"
				(path ""
					(reference "TP54")
					(unit 1)
				)
			)
		)
	)
	(symbol
		(lib_id "antmicroTestPoints:TP_0.75mm_SMD")
		(at 210.82 224.79 0)
		(unit 1)
		(exclude_from_sim no)
		(in_bom no)
		(on_board yes)
		(dnp no)
		(property "Reference" "TP56"
			(at 217.17 224.79 0)
			(effects
				(font
					(size 1.27 1.27)
					(thickness 0.15)
				)
			)
		)
		(property "Value" "TP_0.75mm_SMD"
			(at 221.615 228.6 0)
			(effects
				(font
					(size 1.27 1.27)
					(thickness 0.15)
				)
				(justify left bottom)
				(hide yes)
			)
		)
		(property "Footprint" "antmicro-footprints:TP_SMD_0.75mm"
			(at 221.615 231.14 0)
			(effects
				(font
					(size 1.27 1.27)
					(thickness 0.15)
				)
				(justify left bottom)
				(hide yes)
			)
		)
		(property "Datasheet" ""
			(at 228.6 237.49 0)
			(effects
				(font
					(size 1.27 1.27)
					(thickness 0.15)
				)
				(justify left bottom)
				(hide yes)
			)
		)
		(property "Description" ""
			(at 210.82 224.79 0)
			(effects
				(font
					(size 1.27 1.27)
				)
				(hide yes)
			)
		)
		(property "MPN" ""
			(at 221.615 236.22 0)
			(effects
				(font
					(size 1.27 1.27)
					(thickness 0.15)
				)
				(justify left bottom)
				(hide yes)
			)
		)
		(property "Manufacturer" ""
			(at 221.615 231.14 0)
			(effects
				(font
					(size 1.27 1.27)
					(thickness 0.15)
				)
				(justify left bottom)
				(hide yes)
			)
		)
		(property "Author" "Antmicro"
			(at 221.615 233.68 0)
			(effects
				(font
					(size 1.27 1.27)
					(thickness 0.15)
				)
				(justify left bottom)
				(hide yes)
			)
		)
		(property "License" "Apache-2.0"
			(at 221.615 236.22 0)
			(effects
				(font
					(size 1.27 1.27)
					(thickness 0.15)
				)
				(justify left bottom)
				(hide yes)
			)
		)
		(property "Public" "False"
			(at 220.98 238.76 0)
			(effects
				(font
					(size 1.27 1.27)
				)
				(justify left bottom)
				(hide yes)
			)
		)
		(pin "1"
		)
		(instances
			(project "com-express-7-baseboard"
				(path ""
					(reference "TP56")
					(unit 1)
				)
			)
		)
	)
	(symbol
		(lib_id "antmicroResistors0402:R_1k_0402")
		(at 153.67 97.79 270)
		(unit 1)
		(exclude_from_sim no)
		(in_bom yes)
		(on_board yes)
		(dnp yes)
		(property "Reference" "R208"
			(at 153.67 93.98 0)
			(effects
				(font
					(size 1.27 1.27)
					(thickness 0.15)
				)
				(justify right)
			)
		)
		(property "Value" "R_1k_0402"
			(at 140.97 118.11 0)
			(effects
				(font
					(size 1.27 1.27)
					(thickness 0.15)
				)
				(justify left bottom)
				(hide yes)
			)
		)
		(property "Footprint" "antmicro-footprints:R_0402_1005Metric"
			(at 138.43 118.11 0)
			(effects
				(font
					(size 1.27 1.27)
					(thickness 0.15)
				)
				(justify left bottom)
				(hide yes)
			)
		)
		(property "Datasheet" "https://www.bourns.com/docs/product-datasheets/cr.pdf"
			(at 135.89 118.11 0)
			(effects
				(font
					(size 1.27 1.27)
					(thickness 0.15)
				)
				(justify left bottom)
				(hide yes)
			)
		)
		(property "Description" ""
			(at 153.67 97.79 0)
			(effects
				(font
					(size 1.27 1.27)
				)
				(hide yes)
			)
		)
		(property "MPN" "CR0402-FX-1001GLF"
			(at 133.35 118.11 0)
			(effects
				(font
					(size 1.27 1.27)
					(thickness 0.15)
				)
				(justify left bottom)
				(hide yes)
			)
		)
		(property "Manufacturer" "Bourns"
			(at 130.81 118.11 0)
			(effects
				(font
					(size 1.27 1.27)
					(thickness 0.15)
				)
				(justify left bottom)
				(hide yes)
			)
		)
		(property "License" "Apache-2.0"
			(at 128.27 118.11 0)
			(effects
				(font
					(size 1.27 1.27)
					(thickness 0.15)
				)
				(justify left bottom)
				(hide yes)
			)
		)
		(property "Author" "Antmicro"
			(at 125.73 118.11 0)
			(effects
				(font
					(size 1.27 1.27)
					(thickness 0.15)
				)
				(justify left bottom)
				(hide yes)
			)
		)
		(property "Val" "1k"
			(at 154.94 97.79 0)
			(effects
				(font
					(size 1.27 1.27)
					(thickness 0.15)
				)
				(justify right)
			)
		)
		(property "Tolerance" "1%"
			(at 143.51 118.11 0)
			(effects
				(font
					(size 1.27 1.27)
				)
				(justify left bottom)
				(hide yes)
			)
		)
		(property "Public" "False"
			(at 123.19 118.11 0)
			(effects
				(font
					(size 1.27 1.27)
				)
				(justify left bottom)
				(hide yes)
			)
		)
		(pin "1"
		)
		(pin "2"
		)
		(instances
			(project "com-express-7-baseboard"
				(path ""
					(reference "R208")
					(unit 1)
				)
			)
		)
	)
	(symbol
		(lib_id "antmicroResistors0402:R_1k_0402")
		(at 151.13 97.79 270)
		(unit 1)
		(exclude_from_sim no)
		(in_bom yes)
		(on_board yes)
		(dnp no)
		(property "Reference" "R206"
			(at 151.13 93.98 0)
			(effects
				(font
					(size 1.27 1.27)
					(thickness 0.15)
				)
				(justify right)
			)
		)
		(property "Value" "R_1k_0402"
			(at 138.43 118.11 0)
			(effects
				(font
					(size 1.27 1.27)
					(thickness 0.15)
				)
				(justify left bottom)
				(hide yes)
			)
		)
		(property "Footprint" "antmicro-footprints:R_0402_1005Metric"
			(at 135.89 118.11 0)
			(effects
				(font
					(size 1.27 1.27)
					(thickness 0.15)
				)
				(justify left bottom)
				(hide yes)
			)
		)
		(property "Datasheet" "https://www.bourns.com/docs/product-datasheets/cr.pdf"
			(at 133.35 118.11 0)
			(effects
				(font
					(size 1.27 1.27)
					(thickness 0.15)
				)
				(justify left bottom)
				(hide yes)
			)
		)
		(property "Description" ""
			(at 151.13 97.79 0)
			(effects
				(font
					(size 1.27 1.27)
				)
				(hide yes)
			)
		)
		(property "MPN" "CR0402-FX-1001GLF"
			(at 130.81 118.11 0)
			(effects
				(font
					(size 1.27 1.27)
					(thickness 0.15)
				)
				(justify left bottom)
				(hide yes)
			)
		)
		(property "Manufacturer" "Bourns"
			(at 128.27 118.11 0)
			(effects
				(font
					(size 1.27 1.27)
					(thickness 0.15)
				)
				(justify left bottom)
				(hide yes)
			)
		)
		(property "License" "Apache-2.0"
			(at 125.73 118.11 0)
			(effects
				(font
					(size 1.27 1.27)
					(thickness 0.15)
				)
				(justify left bottom)
				(hide yes)
			)
		)
		(property "Author" "Antmicro"
			(at 123.19 118.11 0)
			(effects
				(font
					(size 1.27 1.27)
					(thickness 0.15)
				)
				(justify left bottom)
				(hide yes)
			)
		)
		(property "Val" "1k"
			(at 152.4 97.79 0)
			(effects
				(font
					(size 1.27 1.27)
					(thickness 0.15)
				)
				(justify right)
			)
		)
		(property "Tolerance" "1%"
			(at 140.97 118.11 0)
			(effects
				(font
					(size 1.27 1.27)
				)
				(justify left bottom)
				(hide yes)
			)
		)
		(property "Public" "False"
			(at 120.65 118.11 0)
			(effects
				(font
					(size 1.27 1.27)
				)
				(justify left bottom)
				(hide yes)
			)
		)
		(pin "1"
		)
		(pin "2"
		)
		(instances
			(project "com-express-7-baseboard"
				(path ""
					(reference "R206")
					(unit 1)
				)
			)
		)
	)
	(symbol
		(lib_id "antmicroCapacitors0402:C_100n_0402")
		(at 152.4 167.64 90)
		(unit 1)
		(exclude_from_sim no)
		(in_bom yes)
		(on_board yes)
		(dnp no)
		(fields_autoplaced yes)
		(property "Reference" "C118"
			(at 154.94 163.8236 90)
			(effects
				(font
					(size 1.27 1.27)
					(thickness 0.15)
				)
				(justify right)
			)
		)
		(property "Value" "C_100n_0402"
			(at 162.56 147.32 0)
			(effects
				(font
					(size 1.27 1.27)
					(thickness 0.15)
				)
				(justify left bottom)
				(hide yes)
			)
		)
		(property "Footprint" "antmicro-footprints:C_0402_1005Metric"
			(at 165.1 147.32 0)
			(effects
				(font
					(size 1.27 1.27)
					(thickness 0.15)
				)
				(justify left bottom)
				(hide yes)
			)
		)
		(property "Datasheet" "https://www.murata.com/products/productdetail?partno=GRM155R61H104KE14%23"
			(at 167.64 147.32 0)
			(effects
				(font
					(size 1.27 1.27)
					(thickness 0.15)
				)
				(justify left bottom)
				(hide yes)
			)
		)
		(property "Description" ""
			(at 152.4 167.64 0)
			(effects
				(font
					(size 1.27 1.27)
				)
				(hide yes)
			)
		)
		(property "MPN" "GRM155R61H104KE14D"
			(at 170.18 147.32 0)
			(effects
				(font
					(size 1.27 1.27)
					(thickness 0.15)
				)
				(justify left bottom)
				(hide yes)
			)
		)
		(property "Manufacturer" "Murata"
			(at 172.72 147.32 0)
			(effects
				(font
					(size 1.27 1.27)
					(thickness 0.15)
				)
				(justify left bottom)
				(hide yes)
			)
		)
		(property "License" "Apache-2.0"
			(at 175.26 147.32 0)
			(effects
				(font
					(size 1.27 1.27)
					(thickness 0.15)
				)
				(justify left bottom)
				(hide yes)
			)
		)
		(property "Author" "Antmicro"
			(at 177.8 147.32 0)
			(effects
				(font
					(size 1.27 1.27)
					(thickness 0.15)
				)
				(justify left bottom)
				(hide yes)
			)
		)
		(property "Val" "100n"
			(at 154.94 166.3636 90)
			(effects
				(font
					(size 1.27 1.27)
					(thickness 0.15)
				)
				(justify right)
			)
		)
		(property "Voltage" "50V"
			(at 180.34 147.32 0)
			(effects
				(font
					(size 1.27 1.27)
				)
				(justify left bottom)
				(hide yes)
			)
		)
		(property "Dielectric" "X5R"
			(at 182.88 147.32 0)
			(effects
				(font
					(size 1.27 1.27)
				)
				(justify left bottom)
				(hide yes)
			)
		)
		(property "Public" "False"
			(at 185.42 147.32 0)
			(effects
				(font
					(size 1.27 1.27)
				)
				(justify left bottom)
				(hide yes)
			)
		)
		(pin "1"
		)
		(pin "2"
		)
		(instances
			(project "com-express-7-baseboard"
				(path ""
					(reference "C118")
					(unit 1)
				)
			)
		)
	)
	(symbol
		(lib_id "antmicroResistors0402:R_1k_0402")
		(at 146.05 127 90)
		(unit 1)
		(exclude_from_sim no)
		(in_bom yes)
		(on_board yes)
		(dnp yes)
		(property "Reference" "R203"
			(at 146.05 130.81 0)
			(effects
				(font
					(size 1.27 1.27)
					(thickness 0.15)
				)
				(justify right)
			)
		)
		(property "Value" "R_1k_0402"
			(at 158.75 106.68 0)
			(effects
				(font
					(size 1.27 1.27)
					(thickness 0.15)
				)
				(justify left bottom)
				(hide yes)
			)
		)
		(property "Footprint" "antmicro-footprints:R_0402_1005Metric"
			(at 161.29 106.68 0)
			(effects
				(font
					(size 1.27 1.27)
					(thickness 0.15)
				)
				(justify left bottom)
				(hide yes)
			)
		)
		(property "Datasheet" "https://www.bourns.com/docs/product-datasheets/cr.pdf"
			(at 163.83 106.68 0)
			(effects
				(font
					(size 1.27 1.27)
					(thickness 0.15)
				)
				(justify left bottom)
				(hide yes)
			)
		)
		(property "Description" ""
			(at 146.05 127 0)
			(effects
				(font
					(size 1.27 1.27)
				)
				(hide yes)
			)
		)
		(property "MPN" "CR0402-FX-1001GLF"
			(at 166.37 106.68 0)
			(effects
				(font
					(size 1.27 1.27)
					(thickness 0.15)
				)
				(justify left bottom)
				(hide yes)
			)
		)
		(property "Manufacturer" "Bourns"
			(at 168.91 106.68 0)
			(effects
				(font
					(size 1.27 1.27)
					(thickness 0.15)
				)
				(justify left bottom)
				(hide yes)
			)
		)
		(property "License" "Apache-2.0"
			(at 171.45 106.68 0)
			(effects
				(font
					(size 1.27 1.27)
					(thickness 0.15)
				)
				(justify left bottom)
				(hide yes)
			)
		)
		(property "Author" "Antmicro"
			(at 173.99 106.68 0)
			(effects
				(font
					(size 1.27 1.27)
					(thickness 0.15)
				)
				(justify left bottom)
				(hide yes)
			)
		)
		(property "Val" "1k"
			(at 144.78 127 0)
			(effects
				(font
					(size 1.27 1.27)
					(thickness 0.15)
				)
				(justify right)
			)
		)
		(property "Tolerance" "1%"
			(at 156.21 106.68 0)
			(effects
				(font
					(size 1.27 1.27)
				)
				(justify left bottom)
				(hide yes)
			)
		)
		(property "Public" "False"
			(at 176.53 106.68 0)
			(effects
				(font
					(size 1.27 1.27)
				)
				(justify left bottom)
				(hide yes)
			)
		)
		(pin "1"
		)
		(pin "2"
		)
		(instances
			(project "com-express-7-baseboard"
				(path ""
					(reference "R203")
					(unit 1)
				)
			)
		)
	)
	(symbol
		(lib_id "antmicropower:GND")
		(at 152.4 152.4 0)
		(unit 1)
		(exclude_from_sim no)
		(in_bom yes)
		(on_board yes)
		(dnp no)
		(property "Reference" "#PWR0299"
			(at 161.29 154.94 0)
			(effects
				(font
					(size 1.27 1.27)
					(thickness 0.15)
				)
				(justify left bottom)
				(hide yes)
			)
		)
		(property "Value" "GND"
			(at 152.4 156.21 0)
			(effects
				(font
					(size 1.27 1.27)
					(thickness 0.15)
				)
			)
		)
		(property "Footprint" ""
			(at 161.29 160.02 0)
			(effects
				(font
					(size 1.27 1.27)
					(thickness 0.15)
				)
				(justify left bottom)
				(hide yes)
			)
		)
		(property "Datasheet" ""
			(at 161.29 165.1 0)
			(effects
				(font
					(size 1.27 1.27)
					(thickness 0.15)
				)
				(justify left bottom)
				(hide yes)
			)
		)
		(property "Description" ""
			(at 152.4 152.4 0)
			(effects
				(font
					(size 1.27 1.27)
				)
				(hide yes)
			)
		)
		(property "Author" "Antmicro"
			(at 161.29 160.02 0)
			(effects
				(font
					(size 1.27 1.27)
					(thickness 0.15)
				)
				(justify left bottom)
				(hide yes)
			)
		)
		(property "License" "Apache-2.0"
			(at 161.29 162.56 0)
			(effects
				(font
					(size 1.27 1.27)
					(thickness 0.15)
				)
				(justify left bottom)
				(hide yes)
			)
		)
		(pin "1"
		)
		(instances
			(project "com-express-7-baseboard"
				(path ""
					(reference "#PWR0299")
					(unit 1)
				)
			)
		)
	)
	(symbol
		(lib_id "antmicropower:GND")
		(at 209.55 123.19 0)
		(unit 1)
		(exclude_from_sim no)
		(in_bom yes)
		(on_board yes)
		(dnp no)
		(property "Reference" "#PWR0316"
			(at 218.44 125.73 0)
			(effects
				(font
					(size 1.27 1.27)
					(thickness 0.15)
				)
				(justify left bottom)
				(hide yes)
			)
		)
		(property "Value" "GND"
			(at 209.55 127 0)
			(effects
				(font
					(size 1.27 1.27)
					(thickness 0.15)
				)
			)
		)
		(property "Footprint" ""
			(at 218.44 130.81 0)
			(effects
				(font
					(size 1.27 1.27)
					(thickness 0.15)
				)
				(justify left bottom)
				(hide yes)
			)
		)
		(property "Datasheet" ""
			(at 218.44 135.89 0)
			(effects
				(font
					(size 1.27 1.27)
					(thickness 0.15)
				)
				(justify left bottom)
				(hide yes)
			)
		)
		(property "Description" ""
			(at 209.55 123.19 0)
			(effects
				(font
					(size 1.27 1.27)
				)
				(hide yes)
			)
		)
		(property "Author" "Antmicro"
			(at 218.44 130.81 0)
			(effects
				(font
					(size 1.27 1.27)
					(thickness 0.15)
				)
				(justify left bottom)
				(hide yes)
			)
		)
		(property "License" "Apache-2.0"
			(at 218.44 133.35 0)
			(effects
				(font
					(size 1.27 1.27)
					(thickness 0.15)
				)
				(justify left bottom)
				(hide yes)
			)
		)
		(pin "1"
		)
		(instances
			(project "com-express-7-baseboard"
				(path ""
					(reference "#PWR0316")
					(unit 1)
				)
			)
		)
	)
	(symbol
		(lib_id "antmicropower:+3V3")
		(at 250.19 217.17 0)
		(mirror y)
		(unit 1)
		(exclude_from_sim no)
		(in_bom yes)
		(on_board yes)
		(dnp no)
		(property "Reference" "#PWR0320"
			(at 234.95 217.17 0)
			(effects
				(font
					(size 1.27 1.27)
					(thickness 0.15)
				)
				(justify left bottom)
				(hide yes)
			)
		)
		(property "Value" "+3V3"
			(at 251.46 213.36 0)
			(effects
				(font
					(size 1.27 1.27)
					(thickness 0.15)
				)
			)
		)
		(property "Footprint" ""
			(at 234.95 224.79 0)
			(effects
				(font
					(size 1.27 1.27)
					(thickness 0.15)
				)
				(justify left bottom)
				(hide yes)
			)
		)
		(property "Datasheet" ""
			(at 234.95 227.33 0)
			(effects
				(font
					(size 1.27 1.27)
					(thickness 0.15)
				)
				(justify left bottom)
				(hide yes)
			)
		)
		(property "Description" ""
			(at 250.19 217.17 0)
			(effects
				(font
					(size 1.27 1.27)
				)
				(hide yes)
			)
		)
		(property "Author" "Antmicro"
			(at 234.95 219.71 0)
			(effects
				(font
					(size 1.27 1.27)
					(thickness 0.15)
				)
				(justify left bottom)
				(hide yes)
			)
		)
		(property "License" "Apache-2.0"
			(at 234.95 222.25 0)
			(effects
				(font
					(size 1.27 1.27)
					(thickness 0.15)
				)
				(justify left bottom)
				(hide yes)
			)
		)
		(pin "1"
		)
		(instances
			(project "com-express-7-baseboard"
				(path ""
					(reference "#PWR0320")
					(unit 1)
				)
			)
		)
	)
	(symbol
		(lib_id "antmicropower:+3V3")
		(at 132.08 21.59 0)
		(unit 1)
		(exclude_from_sim no)
		(in_bom yes)
		(on_board yes)
		(dnp no)
		(fields_autoplaced yes)
		(property "Reference" "#PWR0289"
			(at 147.32 21.59 0)
			(effects
				(font
					(size 1.27 1.27)
					(thickness 0.15)
				)
				(justify left bottom)
				(hide yes)
			)
		)
		(property "Value" "+3V3"
			(at 132.08 16.51 0)
			(effects
				(font
					(size 1.27 1.27)
					(thickness 0.15)
				)
			)
		)
		(property "Footprint" ""
			(at 147.32 29.21 0)
			(effects
				(font
					(size 1.27 1.27)
					(thickness 0.15)
				)
				(justify left bottom)
				(hide yes)
			)
		)
		(property "Datasheet" ""
			(at 147.32 31.75 0)
			(effects
				(font
					(size 1.27 1.27)
					(thickness 0.15)
				)
				(justify left bottom)
				(hide yes)
			)
		)
		(property "Description" ""
			(at 132.08 21.59 0)
			(effects
				(font
					(size 1.27 1.27)
				)
				(hide yes)
			)
		)
		(property "Author" "Antmicro"
			(at 147.32 24.13 0)
			(effects
				(font
					(size 1.27 1.27)
					(thickness 0.15)
				)
				(justify left bottom)
				(hide yes)
			)
		)
		(property "License" "Apache-2.0"
			(at 147.32 26.67 0)
			(effects
				(font
					(size 1.27 1.27)
					(thickness 0.15)
				)
				(justify left bottom)
				(hide yes)
			)
		)
		(pin "1"
		)
		(instances
			(project "com-express-7-baseboard"
				(path ""
					(reference "#PWR0289")
					(unit 1)
				)
			)
		)
	)
	(symbol
		(lib_id "antmicropower:GND")
		(at 140.97 45.72 0)
		(unit 1)
		(exclude_from_sim no)
		(in_bom yes)
		(on_board yes)
		(dnp no)
		(property "Reference" "#PWR0293"
			(at 149.86 48.26 0)
			(effects
				(font
					(size 1.27 1.27)
					(thickness 0.15)
				)
				(justify left bottom)
				(hide yes)
			)
		)
		(property "Value" "GND"
			(at 140.97 49.53 0)
			(effects
				(font
					(size 1.27 1.27)
					(thickness 0.15)
				)
			)
		)
		(property "Footprint" ""
			(at 149.86 53.34 0)
			(effects
				(font
					(size 1.27 1.27)
					(thickness 0.15)
				)
				(justify left bottom)
				(hide yes)
			)
		)
		(property "Datasheet" ""
			(at 149.86 58.42 0)
			(effects
				(font
					(size 1.27 1.27)
					(thickness 0.15)
				)
				(justify left bottom)
				(hide yes)
			)
		)
		(property "Description" ""
			(at 140.97 45.72 0)
			(effects
				(font
					(size 1.27 1.27)
				)
				(hide yes)
			)
		)
		(property "Author" "Antmicro"
			(at 149.86 53.34 0)
			(effects
				(font
					(size 1.27 1.27)
					(thickness 0.15)
				)
				(justify left bottom)
				(hide yes)
			)
		)
		(property "License" "Apache-2.0"
			(at 149.86 55.88 0)
			(effects
				(font
					(size 1.27 1.27)
					(thickness 0.15)
				)
				(justify left bottom)
				(hide yes)
			)
		)
		(pin "1"
		)
		(instances
			(project "com-express-7-baseboard"
				(path ""
					(reference "#PWR0293")
					(unit 1)
				)
			)
		)
	)
	(symbol
		(lib_id "antmicroResistors0402:R_1k_0402")
		(at 240.03 222.25 90)
		(mirror x)
		(unit 1)
		(exclude_from_sim no)
		(in_bom yes)
		(on_board yes)
		(dnp yes)
		(property "Reference" "R223"
			(at 240.03 218.44 0)
			(effects
				(font
					(size 1.27 1.27)
					(thickness 0.15)
				)
				(justify right)
			)
		)
		(property "Value" "R_1k_0402"
			(at 252.73 242.57 0)
			(effects
				(font
					(size 1.27 1.27)
					(thickness 0.15)
				)
				(justify left bottom)
				(hide yes)
			)
		)
		(property "Footprint" "antmicro-footprints:R_0402_1005Metric"
			(at 255.27 242.57 0)
			(effects
				(font
					(size 1.27 1.27)
					(thickness 0.15)
				)
				(justify left bottom)
				(hide yes)
			)
		)
		(property "Datasheet" "https://www.bourns.com/docs/product-datasheets/cr.pdf"
			(at 257.81 242.57 0)
			(effects
				(font
					(size 1.27 1.27)
					(thickness 0.15)
				)
				(justify left bottom)
				(hide yes)
			)
		)
		(property "Description" ""
			(at 240.03 222.25 0)
			(effects
				(font
					(size 1.27 1.27)
				)
				(hide yes)
			)
		)
		(property "MPN" "CR0402-FX-1001GLF"
			(at 260.35 242.57 0)
			(effects
				(font
					(size 1.27 1.27)
					(thickness 0.15)
				)
				(justify left bottom)
				(hide yes)
			)
		)
		(property "Manufacturer" "Bourns"
			(at 262.89 242.57 0)
			(effects
				(font
					(size 1.27 1.27)
					(thickness 0.15)
				)
				(justify left bottom)
				(hide yes)
			)
		)
		(property "License" "Apache-2.0"
			(at 265.43 242.57 0)
			(effects
				(font
					(size 1.27 1.27)
					(thickness 0.15)
				)
				(justify left bottom)
				(hide yes)
			)
		)
		(property "Author" "Antmicro"
			(at 267.97 242.57 0)
			(effects
				(font
					(size 1.27 1.27)
					(thickness 0.15)
				)
				(justify left bottom)
				(hide yes)
			)
		)
		(property "Val" "1k"
			(at 238.76 222.25 0)
			(effects
				(font
					(size 1.27 1.27)
					(thickness 0.15)
				)
				(justify right)
			)
		)
		(property "Tolerance" "1%"
			(at 250.19 242.57 0)
			(effects
				(font
					(size 1.27 1.27)
				)
				(justify left bottom)
				(hide yes)
			)
		)
		(property "Public" "False"
			(at 270.51 242.57 0)
			(effects
				(font
					(size 1.27 1.27)
				)
				(justify left bottom)
				(hide yes)
			)
		)
		(pin "1"
		)
		(pin "2"
		)
		(instances
			(project "com-express-7-baseboard"
				(path ""
					(reference "R223")
					(unit 1)
				)
			)
		)
	)
	(symbol
		(lib_id "antmicroCapacitors0402:C_100n_0402")
		(at 132.08 30.48 90)
		(unit 1)
		(exclude_from_sim no)
		(in_bom yes)
		(on_board yes)
		(dnp no)
		(fields_autoplaced yes)
		(property "Reference" "C111"
			(at 134.62 26.6636 90)
			(effects
				(font
					(size 1.27 1.27)
					(thickness 0.15)
				)
				(justify right)
			)
		)
		(property "Value" "C_100n_0402"
			(at 142.24 10.16 0)
			(effects
				(font
					(size 1.27 1.27)
					(thickness 0.15)
				)
				(justify left bottom)
				(hide yes)
			)
		)
		(property "Footprint" "antmicro-footprints:C_0402_1005Metric"
			(at 144.78 10.16 0)
			(effects
				(font
					(size 1.27 1.27)
					(thickness 0.15)
				)
				(justify left bottom)
				(hide yes)
			)
		)
		(property "Datasheet" "https://www.murata.com/products/productdetail?partno=GRM155R61H104KE14%23"
			(at 147.32 10.16 0)
			(effects
				(font
					(size 1.27 1.27)
					(thickness 0.15)
				)
				(justify left bottom)
				(hide yes)
			)
		)
		(property "Description" ""
			(at 132.08 30.48 0)
			(effects
				(font
					(size 1.27 1.27)
				)
				(hide yes)
			)
		)
		(property "MPN" "GRM155R61H104KE14D"
			(at 149.86 10.16 0)
			(effects
				(font
					(size 1.27 1.27)
					(thickness 0.15)
				)
				(justify left bottom)
				(hide yes)
			)
		)
		(property "Manufacturer" "Murata"
			(at 152.4 10.16 0)
			(effects
				(font
					(size 1.27 1.27)
					(thickness 0.15)
				)
				(justify left bottom)
				(hide yes)
			)
		)
		(property "License" "Apache-2.0"
			(at 154.94 10.16 0)
			(effects
				(font
					(size 1.27 1.27)
					(thickness 0.15)
				)
				(justify left bottom)
				(hide yes)
			)
		)
		(property "Author" "Antmicro"
			(at 157.48 10.16 0)
			(effects
				(font
					(size 1.27 1.27)
					(thickness 0.15)
				)
				(justify left bottom)
				(hide yes)
			)
		)
		(property "Val" "100n"
			(at 134.62 29.2036 90)
			(effects
				(font
					(size 1.27 1.27)
					(thickness 0.15)
				)
				(justify right)
			)
		)
		(property "Voltage" "50V"
			(at 160.02 10.16 0)
			(effects
				(font
					(size 1.27 1.27)
				)
				(justify left bottom)
				(hide yes)
			)
		)
		(property "Dielectric" "X5R"
			(at 162.56 10.16 0)
			(effects
				(font
					(size 1.27 1.27)
				)
				(justify left bottom)
				(hide yes)
			)
		)
		(property "Public" "False"
			(at 165.1 10.16 0)
			(effects
				(font
					(size 1.27 1.27)
				)
				(justify left bottom)
				(hide yes)
			)
		)
		(pin "1"
		)
		(pin "2"
		)
		(instances
			(project "com-express-7-baseboard"
				(path ""
					(reference "C111")
					(unit 1)
				)
			)
		)
	)
	(symbol
		(lib_id "antmicropower:GND")
		(at 149.86 45.72 0)
		(unit 1)
		(exclude_from_sim no)
		(in_bom yes)
		(on_board yes)
		(dnp no)
		(property "Reference" "#PWR0297"
			(at 158.75 48.26 0)
			(effects
				(font
					(size 1.27 1.27)
					(thickness 0.15)
				)
				(justify left bottom)
				(hide yes)
			)
		)
		(property "Value" "GND"
			(at 149.86 49.53 0)
			(effects
				(font
					(size 1.27 1.27)
					(thickness 0.15)
				)
			)
		)
		(property "Footprint" ""
			(at 158.75 53.34 0)
			(effects
				(font
					(size 1.27 1.27)
					(thickness 0.15)
				)
				(justify left bottom)
				(hide yes)
			)
		)
		(property "Datasheet" ""
			(at 158.75 58.42 0)
			(effects
				(font
					(size 1.27 1.27)
					(thickness 0.15)
				)
				(justify left bottom)
				(hide yes)
			)
		)
		(property "Description" ""
			(at 149.86 45.72 0)
			(effects
				(font
					(size 1.27 1.27)
				)
				(hide yes)
			)
		)
		(property "Author" "Antmicro"
			(at 158.75 53.34 0)
			(effects
				(font
					(size 1.27 1.27)
					(thickness 0.15)
				)
				(justify left bottom)
				(hide yes)
			)
		)
		(property "License" "Apache-2.0"
			(at 158.75 55.88 0)
			(effects
				(font
					(size 1.27 1.27)
					(thickness 0.15)
				)
				(justify left bottom)
				(hide yes)
			)
		)
		(pin "1"
		)
		(instances
			(project "com-express-7-baseboard"
				(path ""
					(reference "#PWR0297")
					(unit 1)
				)
			)
		)
	)
	(symbol
		(lib_id "antmicroResistors0402:R_1k_0402")
		(at 153.67 127 90)
		(unit 1)
		(exclude_from_sim no)
		(in_bom yes)
		(on_board yes)
		(dnp no)
		(property "Reference" "R209"
			(at 153.67 130.81 0)
			(effects
				(font
					(size 1.27 1.27)
					(thickness 0.15)
				)
				(justify right)
			)
		)
		(property "Value" "R_1k_0402"
			(at 166.37 106.68 0)
			(effects
				(font
					(size 1.27 1.27)
					(thickness 0.15)
				)
				(justify left bottom)
				(hide yes)
			)
		)
		(property "Footprint" "antmicro-footprints:R_0402_1005Metric"
			(at 168.91 106.68 0)
			(effects
				(font
					(size 1.27 1.27)
					(thickness 0.15)
				)
				(justify left bottom)
				(hide yes)
			)
		)
		(property "Datasheet" "https://www.bourns.com/docs/product-datasheets/cr.pdf"
			(at 171.45 106.68 0)
			(effects
				(font
					(size 1.27 1.27)
					(thickness 0.15)
				)
				(justify left bottom)
				(hide yes)
			)
		)
		(property "Description" ""
			(at 153.67 127 0)
			(effects
				(font
					(size 1.27 1.27)
				)
				(hide yes)
			)
		)
		(property "MPN" "CR0402-FX-1001GLF"
			(at 173.99 106.68 0)
			(effects
				(font
					(size 1.27 1.27)
					(thickness 0.15)
				)
				(justify left bottom)
				(hide yes)
			)
		)
		(property "Manufacturer" "Bourns"
			(at 176.53 106.68 0)
			(effects
				(font
					(size 1.27 1.27)
					(thickness 0.15)
				)
				(justify left bottom)
				(hide yes)
			)
		)
		(property "License" "Apache-2.0"
			(at 179.07 106.68 0)
			(effects
				(font
					(size 1.27 1.27)
					(thickness 0.15)
				)
				(justify left bottom)
				(hide yes)
			)
		)
		(property "Author" "Antmicro"
			(at 181.61 106.68 0)
			(effects
				(font
					(size 1.27 1.27)
					(thickness 0.15)
				)
				(justify left bottom)
				(hide yes)
			)
		)
		(property "Val" "1k"
			(at 152.4 127 0)
			(effects
				(font
					(size 1.27 1.27)
					(thickness 0.15)
				)
				(justify right)
			)
		)
		(property "Tolerance" "1%"
			(at 163.83 106.68 0)
			(effects
				(font
					(size 1.27 1.27)
				)
				(justify left bottom)
				(hide yes)
			)
		)
		(property "Public" "False"
			(at 184.15 106.68 0)
			(effects
				(font
					(size 1.27 1.27)
				)
				(justify left bottom)
				(hide yes)
			)
		)
		(pin "1"
		)
		(pin "2"
		)
		(instances
			(project "com-express-7-baseboard"
				(path ""
					(reference "R209")
					(unit 1)
				)
			)
		)
	)
	(symbol
		(lib_id "antmicroTestPoints:TP_0.75mm_SMD")
		(at 182.88 97.79 0)
		(mirror y)
		(unit 1)
		(exclude_from_sim no)
		(in_bom no)
		(on_board yes)
		(dnp no)
		(property "Reference" "TP51"
			(at 176.53 97.79 0)
			(effects
				(font
					(size 1.27 1.27)
					(thickness 0.15)
				)
			)
		)
		(property "Value" "TP_0.75mm_SMD"
			(at 172.085 101.6 0)
			(effects
				(font
					(size 1.27 1.27)
					(thickness 0.15)
				)
				(justify left bottom)
				(hide yes)
			)
		)
		(property "Footprint" "antmicro-footprints:TP_SMD_0.75mm"
			(at 172.085 104.14 0)
			(effects
				(font
					(size 1.27 1.27)
					(thickness 0.15)
				)
				(justify left bottom)
				(hide yes)
			)
		)
		(property "Datasheet" ""
			(at 165.1 110.49 0)
			(effects
				(font
					(size 1.27 1.27)
					(thickness 0.15)
				)
				(justify left bottom)
				(hide yes)
			)
		)
		(property "Description" ""
			(at 182.88 97.79 0)
			(effects
				(font
					(size 1.27 1.27)
				)
				(hide yes)
			)
		)
		(property "MPN" ""
			(at 172.085 109.22 0)
			(effects
				(font
					(size 1.27 1.27)
					(thickness 0.15)
				)
				(justify left bottom)
				(hide yes)
			)
		)
		(property "Manufacturer" ""
			(at 172.085 104.14 0)
			(effects
				(font
					(size 1.27 1.27)
					(thickness 0.15)
				)
				(justify left bottom)
				(hide yes)
			)
		)
		(property "Author" "Antmicro"
			(at 172.085 106.68 0)
			(effects
				(font
					(size 1.27 1.27)
					(thickness 0.15)
				)
				(justify left bottom)
				(hide yes)
			)
		)
		(property "License" "Apache-2.0"
			(at 172.085 109.22 0)
			(effects
				(font
					(size 1.27 1.27)
					(thickness 0.15)
				)
				(justify left bottom)
				(hide yes)
			)
		)
		(property "Public" "False"
			(at 172.72 111.76 0)
			(effects
				(font
					(size 1.27 1.27)
				)
				(justify left bottom)
				(hide yes)
			)
		)
		(pin "1"
		)
		(instances
			(project "com-express-7-baseboard"
				(path ""
					(reference "TP51")
					(unit 1)
				)
			)
		)
	)
	(symbol
		(lib_id "antmicroTestPoints:TP_0.75mm_SMD")
		(at 182.88 90.17 0)
		(mirror y)
		(unit 1)
		(exclude_from_sim no)
		(in_bom no)
		(on_board yes)
		(dnp no)
		(property "Reference" "TP49"
			(at 176.53 90.17 0)
			(effects
				(font
					(size 1.27 1.27)
					(thickness 0.15)
				)
			)
		)
		(property "Value" "TP_0.75mm_SMD"
			(at 172.085 93.98 0)
			(effects
				(font
					(size 1.27 1.27)
					(thickness 0.15)
				)
				(justify left bottom)
				(hide yes)
			)
		)
		(property "Footprint" "antmicro-footprints:TP_SMD_0.75mm"
			(at 172.085 96.52 0)
			(effects
				(font
					(size 1.27 1.27)
					(thickness 0.15)
				)
				(justify left bottom)
				(hide yes)
			)
		)
		(property "Datasheet" ""
			(at 165.1 102.87 0)
			(effects
				(font
					(size 1.27 1.27)
					(thickness 0.15)
				)
				(justify left bottom)
				(hide yes)
			)
		)
		(property "Description" ""
			(at 182.88 90.17 0)
			(effects
				(font
					(size 1.27 1.27)
				)
				(hide yes)
			)
		)
		(property "MPN" ""
			(at 172.085 101.6 0)
			(effects
				(font
					(size 1.27 1.27)
					(thickness 0.15)
				)
				(justify left bottom)
				(hide yes)
			)
		)
		(property "Manufacturer" ""
			(at 172.085 96.52 0)
			(effects
				(font
					(size 1.27 1.27)
					(thickness 0.15)
				)
				(justify left bottom)
				(hide yes)
			)
		)
		(property "Author" "Antmicro"
			(at 172.085 99.06 0)
			(effects
				(font
					(size 1.27 1.27)
					(thickness 0.15)
				)
				(justify left bottom)
				(hide yes)
			)
		)
		(property "License" "Apache-2.0"
			(at 172.085 101.6 0)
			(effects
				(font
					(size 1.27 1.27)
					(thickness 0.15)
				)
				(justify left bottom)
				(hide yes)
			)
		)
		(property "Public" "False"
			(at 172.72 104.14 0)
			(effects
				(font
					(size 1.27 1.27)
				)
				(justify left bottom)
				(hide yes)
			)
		)
		(pin "1"
		)
		(instances
			(project "com-express-7-baseboard"
				(path ""
					(reference "TP49")
					(unit 1)
				)
			)
		)
	)
	(symbol
		(lib_id "antmicroCapacitors0402:C_220n_0402")
		(at 152.4 209.55 0)
		(unit 1)
		(exclude_from_sim no)
		(in_bom yes)
		(on_board yes)
		(dnp no)
		(property "Reference" "C126"
			(at 151.13 210.82 0)
			(effects
				(font
					(size 1.27 1.27)
					(thickness 0.15)
				)
			)
		)
		(property "Value" "C_220n_0402"
			(at 172.72 219.71 0)
			(effects
				(font
					(size 1.27 1.27)
					(thickness 0.15)
				)
				(justify left bottom)
				(hide yes)
			)
		)
		(property "Footprint" "antmicro-footprints:C_0402_1005Metric"
			(at 172.72 222.25 0)
			(effects
				(font
					(size 1.27 1.27)
					(thickness 0.15)
				)
				(justify left bottom)
				(hide yes)
			)
		)
		(property "Datasheet" "https://www.yageo.com/en/Chart/Download/pdf/CC0402KRX5R6BB224"
			(at 172.72 224.79 0)
			(effects
				(font
					(size 1.27 1.27)
					(thickness 0.15)
				)
				(justify left bottom)
				(hide yes)
			)
		)
		(property "Description" ""
			(at 152.4 209.55 0)
			(effects
				(font
					(size 1.27 1.27)
				)
				(hide yes)
			)
		)
		(property "MPN" "CC0402KRX5R6BB224"
			(at 172.72 227.33 0)
			(effects
				(font
					(size 1.27 1.27)
					(thickness 0.15)
				)
				(justify left bottom)
				(hide yes)
			)
		)
		(property "Manufacturer" "YAGEO"
			(at 172.72 229.87 0)
			(effects
				(font
					(size 1.27 1.27)
					(thickness 0.15)
				)
				(justify left bottom)
				(hide yes)
			)
		)
		(property "License" "Apache-2.0"
			(at 172.72 232.41 0)
			(effects
				(font
					(size 1.27 1.27)
					(thickness 0.15)
				)
				(justify left bottom)
				(hide yes)
			)
		)
		(property "Author" "Antmicro"
			(at 172.72 234.95 0)
			(effects
				(font
					(size 1.27 1.27)
					(thickness 0.15)
				)
				(justify left bottom)
				(hide yes)
			)
		)
		(property "Val" "220n"
			(at 158.75 210.82 0)
			(effects
				(font
					(size 1.27 1.27)
					(thickness 0.15)
				)
			)
		)
		(property "Voltage" ""
			(at 172.72 237.49 0)
			(effects
				(font
					(size 1.27 1.27)
				)
				(justify left bottom)
				(hide yes)
			)
		)
		(property "Dielectric" ""
			(at 172.72 240.03 0)
			(effects
				(font
					(size 1.27 1.27)
				)
				(justify left bottom)
				(hide yes)
			)
		)
		(property "Public" "False"
			(at 172.72 242.57 0)
			(effects
				(font
					(size 1.27 1.27)
				)
				(justify left bottom)
				(hide yes)
			)
		)
		(pin "1"
		)
		(pin "2"
		)
		(instances
			(project "com-express-7-baseboard"
				(path ""
					(reference "C126")
					(unit 1)
				)
			)
		)
	)
	(symbol
		(lib_id "antmicroCapacitors0402:C_220n_0402")
		(at 229.87 69.85 0)
		(unit 1)
		(exclude_from_sim no)
		(in_bom yes)
		(on_board yes)
		(dnp no)
		(property "Reference" "C140"
			(at 228.6 71.12 0)
			(effects
				(font
					(size 1.27 1.27)
					(thickness 0.15)
				)
			)
		)
		(property "Value" "C_220n_0402"
			(at 250.19 80.01 0)
			(effects
				(font
					(size 1.27 1.27)
					(thickness 0.15)
				)
				(justify left bottom)
				(hide yes)
			)
		)
		(property "Footprint" "antmicro-footprints:C_0402_1005Metric"
			(at 250.19 82.55 0)
			(effects
				(font
					(size 1.27 1.27)
					(thickness 0.15)
				)
				(justify left bottom)
				(hide yes)
			)
		)
		(property "Datasheet" "https://www.yageo.com/en/Chart/Download/pdf/CC0402KRX5R6BB224"
			(at 250.19 85.09 0)
			(effects
				(font
					(size 1.27 1.27)
					(thickness 0.15)
				)
				(justify left bottom)
				(hide yes)
			)
		)
		(property "Description" ""
			(at 229.87 69.85 0)
			(effects
				(font
					(size 1.27 1.27)
				)
				(hide yes)
			)
		)
		(property "MPN" "CC0402KRX5R6BB224"
			(at 250.19 87.63 0)
			(effects
				(font
					(size 1.27 1.27)
					(thickness 0.15)
				)
				(justify left bottom)
				(hide yes)
			)
		)
		(property "Manufacturer" "YAGEO"
			(at 250.19 90.17 0)
			(effects
				(font
					(size 1.27 1.27)
					(thickness 0.15)
				)
				(justify left bottom)
				(hide yes)
			)
		)
		(property "License" "Apache-2.0"
			(at 250.19 92.71 0)
			(effects
				(font
					(size 1.27 1.27)
					(thickness 0.15)
				)
				(justify left bottom)
				(hide yes)
			)
		)
		(property "Author" "Antmicro"
			(at 250.19 95.25 0)
			(effects
				(font
					(size 1.27 1.27)
					(thickness 0.15)
				)
				(justify left bottom)
				(hide yes)
			)
		)
		(property "Val" "220n"
			(at 236.22 71.12 0)
			(effects
				(font
					(size 1.27 1.27)
					(thickness 0.15)
				)
			)
		)
		(property "Voltage" ""
			(at 250.19 97.79 0)
			(effects
				(font
					(size 1.27 1.27)
				)
				(justify left bottom)
				(hide yes)
			)
		)
		(property "Dielectric" ""
			(at 250.19 100.33 0)
			(effects
				(font
					(size 1.27 1.27)
				)
				(justify left bottom)
				(hide yes)
			)
		)
		(property "Public" "False"
			(at 250.19 102.87 0)
			(effects
				(font
					(size 1.27 1.27)
				)
				(justify left bottom)
				(hide yes)
			)
		)
		(pin "1"
		)
		(pin "2"
		)
		(instances
			(project "com-express-7-baseboard"
				(path ""
					(reference "C140")
					(unit 1)
				)
			)
		)
	)
	(symbol
		(lib_id "antmicroCapacitors0402:C_100n_0402")
		(at 161.29 152.4 90)
		(unit 1)
		(exclude_from_sim no)
		(in_bom yes)
		(on_board yes)
		(dnp no)
		(fields_autoplaced yes)
		(property "Reference" "C121"
			(at 163.83 148.5836 90)
			(effects
				(font
					(size 1.27 1.27)
					(thickness 0.15)
				)
				(justify right)
			)
		)
		(property "Value" "C_100n_0402"
			(at 171.45 132.08 0)
			(effects
				(font
					(size 1.27 1.27)
					(thickness 0.15)
				)
				(justify left bottom)
				(hide yes)
			)
		)
		(property "Footprint" "antmicro-footprints:C_0402_1005Metric"
			(at 173.99 132.08 0)
			(effects
				(font
					(size 1.27 1.27)
					(thickness 0.15)
				)
				(justify left bottom)
				(hide yes)
			)
		)
		(property "Datasheet" "https://www.murata.com/products/productdetail?partno=GRM155R61H104KE14%23"
			(at 176.53 132.08 0)
			(effects
				(font
					(size 1.27 1.27)
					(thickness 0.15)
				)
				(justify left bottom)
				(hide yes)
			)
		)
		(property "Description" ""
			(at 161.29 152.4 0)
			(effects
				(font
					(size 1.27 1.27)
				)
				(hide yes)
			)
		)
		(property "MPN" "GRM155R61H104KE14D"
			(at 179.07 132.08 0)
			(effects
				(font
					(size 1.27 1.27)
					(thickness 0.15)
				)
				(justify left bottom)
				(hide yes)
			)
		)
		(property "Manufacturer" "Murata"
			(at 181.61 132.08 0)
			(effects
				(font
					(size 1.27 1.27)
					(thickness 0.15)
				)
				(justify left bottom)
				(hide yes)
			)
		)
		(property "License" "Apache-2.0"
			(at 184.15 132.08 0)
			(effects
				(font
					(size 1.27 1.27)
					(thickness 0.15)
				)
				(justify left bottom)
				(hide yes)
			)
		)
		(property "Author" "Antmicro"
			(at 186.69 132.08 0)
			(effects
				(font
					(size 1.27 1.27)
					(thickness 0.15)
				)
				(justify left bottom)
				(hide yes)
			)
		)
		(property "Val" "100n"
			(at 163.83 151.1236 90)
			(effects
				(font
					(size 1.27 1.27)
					(thickness 0.15)
				)
				(justify right)
			)
		)
		(property "Voltage" "50V"
			(at 189.23 132.08 0)
			(effects
				(font
					(size 1.27 1.27)
				)
				(justify left bottom)
				(hide yes)
			)
		)
		(property "Dielectric" "X5R"
			(at 191.77 132.08 0)
			(effects
				(font
					(size 1.27 1.27)
				)
				(justify left bottom)
				(hide yes)
			)
		)
		(property "Public" "False"
			(at 194.31 132.08 0)
			(effects
				(font
					(size 1.27 1.27)
				)
				(justify left bottom)
				(hide yes)
			)
		)
		(pin "1"
		)
		(pin "2"
		)
		(instances
			(project "com-express-7-baseboard"
				(path ""
					(reference "C121")
					(unit 1)
				)
			)
		)
	)
	(symbol
		(lib_id "antmicroResistors0402:R_1k_0402")
		(at 146.05 97.79 270)
		(unit 1)
		(exclude_from_sim no)
		(in_bom yes)
		(on_board yes)
		(dnp no)
		(property "Reference" "R202"
			(at 146.05 93.98 0)
			(effects
				(font
					(size 1.27 1.27)
					(thickness 0.15)
				)
				(justify right)
			)
		)
		(property "Value" "R_1k_0402"
			(at 133.35 118.11 0)
			(effects
				(font
					(size 1.27 1.27)
					(thickness 0.15)
				)
				(justify left bottom)
				(hide yes)
			)
		)
		(property "Footprint" "antmicro-footprints:R_0402_1005Metric"
			(at 130.81 118.11 0)
			(effects
				(font
					(size 1.27 1.27)
					(thickness 0.15)
				)
				(justify left bottom)
				(hide yes)
			)
		)
		(property "Datasheet" "https://www.bourns.com/docs/product-datasheets/cr.pdf"
			(at 128.27 118.11 0)
			(effects
				(font
					(size 1.27 1.27)
					(thickness 0.15)
				)
				(justify left bottom)
				(hide yes)
			)
		)
		(property "Description" ""
			(at 146.05 97.79 0)
			(effects
				(font
					(size 1.27 1.27)
				)
				(hide yes)
			)
		)
		(property "MPN" "CR0402-FX-1001GLF"
			(at 125.73 118.11 0)
			(effects
				(font
					(size 1.27 1.27)
					(thickness 0.15)
				)
				(justify left bottom)
				(hide yes)
			)
		)
		(property "Manufacturer" "Bourns"
			(at 123.19 118.11 0)
			(effects
				(font
					(size 1.27 1.27)
					(thickness 0.15)
				)
				(justify left bottom)
				(hide yes)
			)
		)
		(property "License" "Apache-2.0"
			(at 120.65 118.11 0)
			(effects
				(font
					(size 1.27 1.27)
					(thickness 0.15)
				)
				(justify left bottom)
				(hide yes)
			)
		)
		(property "Author" "Antmicro"
			(at 118.11 118.11 0)
			(effects
				(font
					(size 1.27 1.27)
					(thickness 0.15)
				)
				(justify left bottom)
				(hide yes)
			)
		)
		(property "Val" "1k"
			(at 147.32 97.79 0)
			(effects
				(font
					(size 1.27 1.27)
					(thickness 0.15)
				)
				(justify right)
			)
		)
		(property "Tolerance" "1%"
			(at 135.89 118.11 0)
			(effects
				(font
					(size 1.27 1.27)
				)
				(justify left bottom)
				(hide yes)
			)
		)
		(property "Public" "False"
			(at 115.57 118.11 0)
			(effects
				(font
					(size 1.27 1.27)
				)
				(justify left bottom)
				(hide yes)
			)
		)
		(pin "1"
		)
		(pin "2"
		)
		(instances
			(project "com-express-7-baseboard"
				(path ""
					(reference "R202")
					(unit 1)
				)
			)
		)
	)
	(symbol
		(lib_id "antmicroCapacitors0402:C_100n_0402")
		(at 170.18 167.64 90)
		(unit 1)
		(exclude_from_sim no)
		(in_bom yes)
		(on_board yes)
		(dnp no)
		(fields_autoplaced yes)
		(property "Reference" "C134"
			(at 172.72 163.8236 90)
			(effects
				(font
					(size 1.27 1.27)
					(thickness 0.15)
				)
				(justify right)
			)
		)
		(property "Value" "C_100n_0402"
			(at 180.34 147.32 0)
			(effects
				(font
					(size 1.27 1.27)
					(thickness 0.15)
				)
				(justify left bottom)
				(hide yes)
			)
		)
		(property "Footprint" "antmicro-footprints:C_0402_1005Metric"
			(at 182.88 147.32 0)
			(effects
				(font
					(size 1.27 1.27)
					(thickness 0.15)
				)
				(justify left bottom)
				(hide yes)
			)
		)
		(property "Datasheet" "https://www.murata.com/products/productdetail?partno=GRM155R61H104KE14%23"
			(at 185.42 147.32 0)
			(effects
				(font
					(size 1.27 1.27)
					(thickness 0.15)
				)
				(justify left bottom)
				(hide yes)
			)
		)
		(property "Description" ""
			(at 170.18 167.64 0)
			(effects
				(font
					(size 1.27 1.27)
				)
				(hide yes)
			)
		)
		(property "MPN" "GRM155R61H104KE14D"
			(at 187.96 147.32 0)
			(effects
				(font
					(size 1.27 1.27)
					(thickness 0.15)
				)
				(justify left bottom)
				(hide yes)
			)
		)
		(property "Manufacturer" "Murata"
			(at 190.5 147.32 0)
			(effects
				(font
					(size 1.27 1.27)
					(thickness 0.15)
				)
				(justify left bottom)
				(hide yes)
			)
		)
		(property "License" "Apache-2.0"
			(at 193.04 147.32 0)
			(effects
				(font
					(size 1.27 1.27)
					(thickness 0.15)
				)
				(justify left bottom)
				(hide yes)
			)
		)
		(property "Author" "Antmicro"
			(at 195.58 147.32 0)
			(effects
				(font
					(size 1.27 1.27)
					(thickness 0.15)
				)
				(justify left bottom)
				(hide yes)
			)
		)
		(property "Val" "100n"
			(at 172.72 166.3636 90)
			(effects
				(font
					(size 1.27 1.27)
					(thickness 0.15)
				)
				(justify right)
			)
		)
		(property "Voltage" "50V"
			(at 198.12 147.32 0)
			(effects
				(font
					(size 1.27 1.27)
				)
				(justify left bottom)
				(hide yes)
			)
		)
		(property "Dielectric" "X5R"
			(at 200.66 147.32 0)
			(effects
				(font
					(size 1.27 1.27)
				)
				(justify left bottom)
				(hide yes)
			)
		)
		(property "Public" "False"
			(at 203.2 147.32 0)
			(effects
				(font
					(size 1.27 1.27)
				)
				(justify left bottom)
				(hide yes)
			)
		)
		(pin "1"
		)
		(pin "2"
		)
		(instances
			(project "com-express-7-baseboard"
				(path ""
					(reference "C134")
					(unit 1)
				)
			)
		)
	)
	(symbol
		(lib_id "antmicroCapacitors0402:C_220n_0402")
		(at 229.87 85.09 0)
		(unit 1)
		(exclude_from_sim no)
		(in_bom yes)
		(on_board yes)
		(dnp no)
		(property "Reference" "C142"
			(at 228.6 86.36 0)
			(effects
				(font
					(size 1.27 1.27)
					(thickness 0.15)
				)
			)
		)
		(property "Value" "C_220n_0402"
			(at 250.19 95.25 0)
			(effects
				(font
					(size 1.27 1.27)
					(thickness 0.15)
				)
				(justify left bottom)
				(hide yes)
			)
		)
		(property "Footprint" "antmicro-footprints:C_0402_1005Metric"
			(at 250.19 97.79 0)
			(effects
				(font
					(size 1.27 1.27)
					(thickness 0.15)
				)
				(justify left bottom)
				(hide yes)
			)
		)
		(property "Datasheet" "https://www.yageo.com/en/Chart/Download/pdf/CC0402KRX5R6BB224"
			(at 250.19 100.33 0)
			(effects
				(font
					(size 1.27 1.27)
					(thickness 0.15)
				)
				(justify left bottom)
				(hide yes)
			)
		)
		(property "Description" ""
			(at 229.87 85.09 0)
			(effects
				(font
					(size 1.27 1.27)
				)
				(hide yes)
			)
		)
		(property "MPN" "CC0402KRX5R6BB224"
			(at 250.19 102.87 0)
			(effects
				(font
					(size 1.27 1.27)
					(thickness 0.15)
				)
				(justify left bottom)
				(hide yes)
			)
		)
		(property "Manufacturer" "YAGEO"
			(at 250.19 105.41 0)
			(effects
				(font
					(size 1.27 1.27)
					(thickness 0.15)
				)
				(justify left bottom)
				(hide yes)
			)
		)
		(property "License" "Apache-2.0"
			(at 250.19 107.95 0)
			(effects
				(font
					(size 1.27 1.27)
					(thickness 0.15)
				)
				(justify left bottom)
				(hide yes)
			)
		)
		(property "Author" "Antmicro"
			(at 250.19 110.49 0)
			(effects
				(font
					(size 1.27 1.27)
					(thickness 0.15)
				)
				(justify left bottom)
				(hide yes)
			)
		)
		(property "Val" "220n"
			(at 236.22 86.36 0)
			(effects
				(font
					(size 1.27 1.27)
					(thickness 0.15)
				)
			)
		)
		(property "Voltage" ""
			(at 250.19 113.03 0)
			(effects
				(font
					(size 1.27 1.27)
				)
				(justify left bottom)
				(hide yes)
			)
		)
		(property "Dielectric" ""
			(at 250.19 115.57 0)
			(effects
				(font
					(size 1.27 1.27)
				)
				(justify left bottom)
				(hide yes)
			)
		)
		(property "Public" "False"
			(at 250.19 118.11 0)
			(effects
				(font
					(size 1.27 1.27)
				)
				(justify left bottom)
				(hide yes)
			)
		)
		(pin "1"
		)
		(pin "2"
		)
		(instances
			(project "com-express-7-baseboard"
				(path ""
					(reference "C142")
					(unit 1)
				)
			)
		)
	)
	(symbol
		(lib_id "antmicroCapacitors0402:C_220n_0402")
		(at 232.41 59.69 0)
		(unit 1)
		(exclude_from_sim no)
		(in_bom yes)
		(on_board yes)
		(dnp no)
		(property "Reference" "C143"
			(at 231.14 58.42 0)
			(effects
				(font
					(size 1.27 1.27)
					(thickness 0.15)
				)
			)
		)
		(property "Value" "C_220n_0402"
			(at 252.73 69.85 0)
			(effects
				(font
					(size 1.27 1.27)
					(thickness 0.15)
				)
				(justify left bottom)
				(hide yes)
			)
		)
		(property "Footprint" "antmicro-footprints:C_0402_1005Metric"
			(at 252.73 72.39 0)
			(effects
				(font
					(size 1.27 1.27)
					(thickness 0.15)
				)
				(justify left bottom)
				(hide yes)
			)
		)
		(property "Datasheet" "https://www.yageo.com/en/Chart/Download/pdf/CC0402KRX5R6BB224"
			(at 252.73 74.93 0)
			(effects
				(font
					(size 1.27 1.27)
					(thickness 0.15)
				)
				(justify left bottom)
				(hide yes)
			)
		)
		(property "Description" ""
			(at 232.41 59.69 0)
			(effects
				(font
					(size 1.27 1.27)
				)
				(hide yes)
			)
		)
		(property "MPN" "CC0402KRX5R6BB224"
			(at 252.73 77.47 0)
			(effects
				(font
					(size 1.27 1.27)
					(thickness 0.15)
				)
				(justify left bottom)
				(hide yes)
			)
		)
		(property "Manufacturer" "YAGEO"
			(at 252.73 80.01 0)
			(effects
				(font
					(size 1.27 1.27)
					(thickness 0.15)
				)
				(justify left bottom)
				(hide yes)
			)
		)
		(property "License" "Apache-2.0"
			(at 252.73 82.55 0)
			(effects
				(font
					(size 1.27 1.27)
					(thickness 0.15)
				)
				(justify left bottom)
				(hide yes)
			)
		)
		(property "Author" "Antmicro"
			(at 252.73 85.09 0)
			(effects
				(font
					(size 1.27 1.27)
					(thickness 0.15)
				)
				(justify left bottom)
				(hide yes)
			)
		)
		(property "Val" "220n"
			(at 238.76 58.42 0)
			(effects
				(font
					(size 1.27 1.27)
					(thickness 0.15)
				)
			)
		)
		(property "Voltage" ""
			(at 252.73 87.63 0)
			(effects
				(font
					(size 1.27 1.27)
				)
				(justify left bottom)
				(hide yes)
			)
		)
		(property "Dielectric" ""
			(at 252.73 90.17 0)
			(effects
				(font
					(size 1.27 1.27)
				)
				(justify left bottom)
				(hide yes)
			)
		)
		(property "Public" "False"
			(at 252.73 92.71 0)
			(effects
				(font
					(size 1.27 1.27)
				)
				(justify left bottom)
				(hide yes)
			)
		)
		(pin "1"
		)
		(pin "2"
		)
		(instances
			(project "com-express-7-baseboard"
				(path ""
					(reference "C143")
					(unit 1)
				)
			)
		)
	)
	(symbol
		(lib_id "antmicroTestPoints:TP_0.75mm_SMD")
		(at 182.88 92.71 0)
		(mirror y)
		(unit 1)
		(exclude_from_sim no)
		(in_bom no)
		(on_board yes)
		(dnp no)
		(property "Reference" "TP50"
			(at 176.53 92.71 0)
			(effects
				(font
					(size 1.27 1.27)
					(thickness 0.15)
				)
			)
		)
		(property "Value" "TP_0.75mm_SMD"
			(at 172.085 96.52 0)
			(effects
				(font
					(size 1.27 1.27)
					(thickness 0.15)
				)
				(justify left bottom)
				(hide yes)
			)
		)
		(property "Footprint" "antmicro-footprints:TP_SMD_0.75mm"
			(at 172.085 99.06 0)
			(effects
				(font
					(size 1.27 1.27)
					(thickness 0.15)
				)
				(justify left bottom)
				(hide yes)
			)
		)
		(property "Datasheet" ""
			(at 165.1 105.41 0)
			(effects
				(font
					(size 1.27 1.27)
					(thickness 0.15)
				)
				(justify left bottom)
				(hide yes)
			)
		)
		(property "Description" ""
			(at 182.88 92.71 0)
			(effects
				(font
					(size 1.27 1.27)
				)
				(hide yes)
			)
		)
		(property "MPN" ""
			(at 172.085 104.14 0)
			(effects
				(font
					(size 1.27 1.27)
					(thickness 0.15)
				)
				(justify left bottom)
				(hide yes)
			)
		)
		(property "Manufacturer" ""
			(at 172.085 99.06 0)
			(effects
				(font
					(size 1.27 1.27)
					(thickness 0.15)
				)
				(justify left bottom)
				(hide yes)
			)
		)
		(property "Author" "Antmicro"
			(at 172.085 101.6 0)
			(effects
				(font
					(size 1.27 1.27)
					(thickness 0.15)
				)
				(justify left bottom)
				(hide yes)
			)
		)
		(property "License" "Apache-2.0"
			(at 172.085 104.14 0)
			(effects
				(font
					(size 1.27 1.27)
					(thickness 0.15)
				)
				(justify left bottom)
				(hide yes)
			)
		)
		(property "Public" "False"
			(at 172.72 106.68 0)
			(effects
				(font
					(size 1.27 1.27)
				)
				(justify left bottom)
				(hide yes)
			)
		)
		(pin "1"
		)
		(instances
			(project "com-express-7-baseboard"
				(path ""
					(reference "TP50")
					(unit 1)
				)
			)
		)
	)
	(symbol
		(lib_id "antmicroResistors0402:R_0R_0402")
		(at 214.63 95.25 180)
		(unit 1)
		(exclude_from_sim no)
		(in_bom yes)
		(on_board yes)
		(dnp no)
		(property "Reference" "R216"
			(at 212.09 97.79 0)
			(effects
				(font
					(size 1.27 1.27)
					(thickness 0.15)
				)
			)
		)
		(property "Value" "R_0R_0402"
			(at 194.31 82.55 0)
			(effects
				(font
					(size 1.27 1.27)
					(thickness 0.15)
				)
				(justify left bottom)
				(hide yes)
			)
		)
		(property "Footprint" "antmicro-footprints:R_0402_1005Metric"
			(at 194.31 80.01 0)
			(effects
				(font
					(size 1.27 1.27)
					(thickness 0.15)
				)
				(justify left bottom)
				(hide yes)
			)
		)
		(property "Datasheet" "https://industrial.panasonic.com/cdbs/www-data/pdf/RDA0000/AOA0000C301.pdf"
			(at 194.31 77.47 0)
			(effects
				(font
					(size 1.27 1.27)
					(thickness 0.15)
				)
				(justify left bottom)
				(hide yes)
			)
		)
		(property "Description" ""
			(at 214.63 95.25 0)
			(effects
				(font
					(size 1.27 1.27)
				)
				(hide yes)
			)
		)
		(property "MPN" "ERJ2GE0R00X"
			(at 194.31 74.93 0)
			(effects
				(font
					(size 1.27 1.27)
					(thickness 0.15)
				)
				(justify left bottom)
				(hide yes)
			)
		)
		(property "Manufacturer" "Panasonic"
			(at 194.31 72.39 0)
			(effects
				(font
					(size 1.27 1.27)
					(thickness 0.15)
				)
				(justify left bottom)
				(hide yes)
			)
		)
		(property "License" "Apache-2.0"
			(at 194.31 69.85 0)
			(effects
				(font
					(size 1.27 1.27)
					(thickness 0.15)
				)
				(justify left bottom)
				(hide yes)
			)
		)
		(property "Author" "Antmicro"
			(at 194.31 67.31 0)
			(effects
				(font
					(size 1.27 1.27)
					(thickness 0.15)
				)
				(justify left bottom)
				(hide yes)
			)
		)
		(property "Val" "0R"
			(at 212.09 100.33 0)
			(effects
				(font
					(size 1.27 1.27)
					(thickness 0.15)
				)
			)
		)
		(property "Tolerance" "~"
			(at 194.31 85.09 0)
			(effects
				(font
					(size 1.27 1.27)
				)
				(justify left bottom)
				(hide yes)
			)
		)
		(property "Current" "1A"
			(at 194.31 64.77 0)
			(effects
				(font
					(size 1.27 1.27)
					(thickness 0.15)
				)
				(justify left bottom)
				(hide yes)
			)
		)
		(property "Public" "False"
			(at 194.31 64.77 0)
			(effects
				(font
					(size 1.27 1.27)
				)
				(justify left bottom)
				(hide yes)
			)
		)
		(pin "1"
		)
		(pin "2"
		)
		(instances
			(project "com-express-7-baseboard"
				(path ""
					(reference "R216")
					(unit 1)
				)
			)
		)
	)
	(symbol
		(lib_id "antmicropower:GND")
		(at 152.4 167.64 0)
		(unit 1)
		(exclude_from_sim no)
		(in_bom yes)
		(on_board yes)
		(dnp no)
		(property "Reference" "#PWR0300"
			(at 161.29 170.18 0)
			(effects
				(font
					(size 1.27 1.27)
					(thickness 0.15)
				)
				(justify left bottom)
				(hide yes)
			)
		)
		(property "Value" "GND"
			(at 152.4 171.45 0)
			(effects
				(font
					(size 1.27 1.27)
					(thickness 0.15)
				)
			)
		)
		(property "Footprint" ""
			(at 161.29 175.26 0)
			(effects
				(font
					(size 1.27 1.27)
					(thickness 0.15)
				)
				(justify left bottom)
				(hide yes)
			)
		)
		(property "Datasheet" ""
			(at 161.29 180.34 0)
			(effects
				(font
					(size 1.27 1.27)
					(thickness 0.15)
				)
				(justify left bottom)
				(hide yes)
			)
		)
		(property "Description" ""
			(at 152.4 167.64 0)
			(effects
				(font
					(size 1.27 1.27)
				)
				(hide yes)
			)
		)
		(property "Author" "Antmicro"
			(at 161.29 175.26 0)
			(effects
				(font
					(size 1.27 1.27)
					(thickness 0.15)
				)
				(justify left bottom)
				(hide yes)
			)
		)
		(property "License" "Apache-2.0"
			(at 161.29 177.8 0)
			(effects
				(font
					(size 1.27 1.27)
					(thickness 0.15)
				)
				(justify left bottom)
				(hide yes)
			)
		)
		(pin "1"
		)
		(instances
			(project "com-express-7-baseboard"
				(path ""
					(reference "#PWR0300")
					(unit 1)
				)
			)
		)
	)
	(symbol
		(lib_id "antmicroResistors0402:R_1k_0402")
		(at 156.21 97.79 270)
		(unit 1)
		(exclude_from_sim no)
		(in_bom yes)
		(on_board yes)
		(dnp no)
		(property "Reference" "R210"
			(at 156.21 93.98 0)
			(effects
				(font
					(size 1.27 1.27)
					(thickness 0.15)
				)
				(justify right)
			)
		)
		(property "Value" "R_1k_0402"
			(at 143.51 118.11 0)
			(effects
				(font
					(size 1.27 1.27)
					(thickness 0.15)
				)
				(justify left bottom)
				(hide yes)
			)
		)
		(property "Footprint" "antmicro-footprints:R_0402_1005Metric"
			(at 140.97 118.11 0)
			(effects
				(font
					(size 1.27 1.27)
					(thickness 0.15)
				)
				(justify left bottom)
				(hide yes)
			)
		)
		(property "Datasheet" "https://www.bourns.com/docs/product-datasheets/cr.pdf"
			(at 138.43 118.11 0)
			(effects
				(font
					(size 1.27 1.27)
					(thickness 0.15)
				)
				(justify left bottom)
				(hide yes)
			)
		)
		(property "Description" ""
			(at 156.21 97.79 0)
			(effects
				(font
					(size 1.27 1.27)
				)
				(hide yes)
			)
		)
		(property "MPN" "CR0402-FX-1001GLF"
			(at 135.89 118.11 0)
			(effects
				(font
					(size 1.27 1.27)
					(thickness 0.15)
				)
				(justify left bottom)
				(hide yes)
			)
		)
		(property "Manufacturer" "Bourns"
			(at 133.35 118.11 0)
			(effects
				(font
					(size 1.27 1.27)
					(thickness 0.15)
				)
				(justify left bottom)
				(hide yes)
			)
		)
		(property "License" "Apache-2.0"
			(at 130.81 118.11 0)
			(effects
				(font
					(size 1.27 1.27)
					(thickness 0.15)
				)
				(justify left bottom)
				(hide yes)
			)
		)
		(property "Author" "Antmicro"
			(at 128.27 118.11 0)
			(effects
				(font
					(size 1.27 1.27)
					(thickness 0.15)
				)
				(justify left bottom)
				(hide yes)
			)
		)
		(property "Val" "1k"
			(at 157.48 97.79 0)
			(effects
				(font
					(size 1.27 1.27)
					(thickness 0.15)
				)
				(justify right)
			)
		)
		(property "Tolerance" "1%"
			(at 146.05 118.11 0)
			(effects
				(font
					(size 1.27 1.27)
				)
				(justify left bottom)
				(hide yes)
			)
		)
		(property "Public" "False"
			(at 125.73 118.11 0)
			(effects
				(font
					(size 1.27 1.27)
				)
				(justify left bottom)
				(hide yes)
			)
		)
		(pin "1"
		)
		(pin "2"
		)
		(instances
			(project "com-express-7-baseboard"
				(path ""
					(reference "R210")
					(unit 1)
				)
			)
		)
	)
	(symbol
		(lib_id "antmicroResistors0402:R_0R_0402")
		(at 222.25 219.71 0)
		(mirror x)
		(unit 1)
		(exclude_from_sim no)
		(in_bom yes)
		(on_board yes)
		(dnp no)
		(property "Reference" "R217"
			(at 232.41 218.44 0)
			(effects
				(font
					(size 1.27 1.27)
					(thickness 0.15)
				)
				(justify right)
			)
		)
		(property "Value" "R_0R_0402"
			(at 242.57 207.01 0)
			(effects
				(font
					(size 1.27 1.27)
					(thickness 0.15)
				)
				(justify left bottom)
				(hide yes)
			)
		)
		(property "Footprint" "antmicro-footprints:R_0402_1005Metric"
			(at 242.57 204.47 0)
			(effects
				(font
					(size 1.27 1.27)
					(thickness 0.15)
				)
				(justify left bottom)
				(hide yes)
			)
		)
		(property "Datasheet" "https://industrial.panasonic.com/cdbs/www-data/pdf/RDA0000/AOA0000C301.pdf"
			(at 242.57 201.93 0)
			(effects
				(font
					(size 1.27 1.27)
					(thickness 0.15)
				)
				(justify left bottom)
				(hide yes)
			)
		)
		(property "Description" ""
			(at 222.25 219.71 0)
			(effects
				(font
					(size 1.27 1.27)
				)
				(hide yes)
			)
		)
		(property "MPN" "ERJ2GE0R00X"
			(at 242.57 199.39 0)
			(effects
				(font
					(size 1.27 1.27)
					(thickness 0.15)
				)
				(justify left bottom)
				(hide yes)
			)
		)
		(property "Manufacturer" "Panasonic"
			(at 242.57 196.85 0)
			(effects
				(font
					(size 1.27 1.27)
					(thickness 0.15)
				)
				(justify left bottom)
				(hide yes)
			)
		)
		(property "License" "Apache-2.0"
			(at 242.57 194.31 0)
			(effects
				(font
					(size 1.27 1.27)
					(thickness 0.15)
				)
				(justify left bottom)
				(hide yes)
			)
		)
		(property "Author" "Antmicro"
			(at 242.57 191.77 0)
			(effects
				(font
					(size 1.27 1.27)
					(thickness 0.15)
				)
				(justify left bottom)
				(hide yes)
			)
		)
		(property "Val" "0R"
			(at 222.25 218.44 0)
			(effects
				(font
					(size 1.27 1.27)
					(thickness 0.15)
				)
				(justify right)
			)
		)
		(property "Tolerance" "~"
			(at 242.57 209.55 0)
			(effects
				(font
					(size 1.27 1.27)
				)
				(justify left bottom)
				(hide yes)
			)
		)
		(property "Current" "1A"
			(at 242.57 189.23 0)
			(effects
				(font
					(size 1.27 1.27)
					(thickness 0.15)
				)
				(justify left bottom)
				(hide yes)
			)
		)
		(property "Public" "False"
			(at 242.57 189.23 0)
			(effects
				(font
					(size 1.27 1.27)
				)
				(justify left bottom)
				(hide yes)
			)
		)
		(pin "1"
		)
		(pin "2"
		)
		(instances
			(project "com-express-7-baseboard"
				(path ""
					(reference "R217")
					(unit 1)
				)
			)
		)
	)
	(symbol
		(lib_id "antmicropower:GND")
		(at 149.86 30.48 0)
		(unit 1)
		(exclude_from_sim no)
		(in_bom yes)
		(on_board yes)
		(dnp no)
		(property "Reference" "#PWR0296"
			(at 158.75 33.02 0)
			(effects
				(font
					(size 1.27 1.27)
					(thickness 0.15)
				)
				(justify left bottom)
				(hide yes)
			)
		)
		(property "Value" "GND"
			(at 149.86 34.29 0)
			(effects
				(font
					(size 1.27 1.27)
					(thickness 0.15)
				)
			)
		)
		(property "Footprint" ""
			(at 158.75 38.1 0)
			(effects
				(font
					(size 1.27 1.27)
					(thickness 0.15)
				)
				(justify left bottom)
				(hide yes)
			)
		)
		(property "Datasheet" ""
			(at 158.75 43.18 0)
			(effects
				(font
					(size 1.27 1.27)
					(thickness 0.15)
				)
				(justify left bottom)
				(hide yes)
			)
		)
		(property "Description" ""
			(at 149.86 30.48 0)
			(effects
				(font
					(size 1.27 1.27)
				)
				(hide yes)
			)
		)
		(property "Author" "Antmicro"
			(at 158.75 38.1 0)
			(effects
				(font
					(size 1.27 1.27)
					(thickness 0.15)
				)
				(justify left bottom)
				(hide yes)
			)
		)
		(property "License" "Apache-2.0"
			(at 158.75 40.64 0)
			(effects
				(font
					(size 1.27 1.27)
					(thickness 0.15)
				)
				(justify left bottom)
				(hide yes)
			)
		)
		(pin "1"
		)
		(instances
			(project "com-express-7-baseboard"
				(path ""
					(reference "#PWR0296")
					(unit 1)
				)
			)
		)
	)
	(symbol
		(lib_id "antmicroResistors0402:R_1k_0402")
		(at 237.49 251.46 270)
		(mirror x)
		(unit 1)
		(exclude_from_sim no)
		(in_bom yes)
		(on_board yes)
		(dnp yes)
		(property "Reference" "R222"
			(at 237.49 255.27 0)
			(effects
				(font
					(size 1.27 1.27)
					(thickness 0.15)
				)
				(justify right)
			)
		)
		(property "Value" "R_1k_0402"
			(at 224.79 231.14 0)
			(effects
				(font
					(size 1.27 1.27)
					(thickness 0.15)
				)
				(justify left bottom)
				(hide yes)
			)
		)
		(property "Footprint" "antmicro-footprints:R_0402_1005Metric"
			(at 222.25 231.14 0)
			(effects
				(font
					(size 1.27 1.27)
					(thickness 0.15)
				)
				(justify left bottom)
				(hide yes)
			)
		)
		(property "Datasheet" "https://www.bourns.com/docs/product-datasheets/cr.pdf"
			(at 219.71 231.14 0)
			(effects
				(font
					(size 1.27 1.27)
					(thickness 0.15)
				)
				(justify left bottom)
				(hide yes)
			)
		)
		(property "Description" ""
			(at 237.49 251.46 0)
			(effects
				(font
					(size 1.27 1.27)
				)
				(hide yes)
			)
		)
		(property "MPN" "CR0402-FX-1001GLF"
			(at 217.17 231.14 0)
			(effects
				(font
					(size 1.27 1.27)
					(thickness 0.15)
				)
				(justify left bottom)
				(hide yes)
			)
		)
		(property "Manufacturer" "Bourns"
			(at 214.63 231.14 0)
			(effects
				(font
					(size 1.27 1.27)
					(thickness 0.15)
				)
				(justify left bottom)
				(hide yes)
			)
		)
		(property "License" "Apache-2.0"
			(at 212.09 231.14 0)
			(effects
				(font
					(size 1.27 1.27)
					(thickness 0.15)
				)
				(justify left bottom)
				(hide yes)
			)
		)
		(property "Author" "Antmicro"
			(at 209.55 231.14 0)
			(effects
				(font
					(size 1.27 1.27)
					(thickness 0.15)
				)
				(justify left bottom)
				(hide yes)
			)
		)
		(property "Val" "1k"
			(at 238.76 251.46 0)
			(effects
				(font
					(size 1.27 1.27)
					(thickness 0.15)
				)
				(justify right)
			)
		)
		(property "Tolerance" "1%"
			(at 227.33 231.14 0)
			(effects
				(font
					(size 1.27 1.27)
				)
				(justify left bottom)
				(hide yes)
			)
		)
		(property "Public" "False"
			(at 207.01 231.14 0)
			(effects
				(font
					(size 1.27 1.27)
				)
				(justify left bottom)
				(hide yes)
			)
		)
		(pin "1"
		)
		(pin "2"
		)
		(instances
			(project "com-express-7-baseboard"
				(path ""
					(reference "R222")
					(unit 1)
				)
			)
		)
	)
	(symbol
		(lib_id "antmicroCapacitors0402:C_100n_0402")
		(at 149.86 30.48 90)
		(unit 1)
		(exclude_from_sim no)
		(in_bom yes)
		(on_board yes)
		(dnp no)
		(fields_autoplaced yes)
		(property "Reference" "C115"
			(at 152.4 26.6636 90)
			(effects
				(font
					(size 1.27 1.27)
					(thickness 0.15)
				)
				(justify right)
			)
		)
		(property "Value" "C_100n_0402"
			(at 160.02 10.16 0)
			(effects
				(font
					(size 1.27 1.27)
					(thickness 0.15)
				)
				(justify left bottom)
				(hide yes)
			)
		)
		(property "Footprint" "antmicro-footprints:C_0402_1005Metric"
			(at 162.56 10.16 0)
			(effects
				(font
					(size 1.27 1.27)
					(thickness 0.15)
				)
				(justify left bottom)
				(hide yes)
			)
		)
		(property "Datasheet" "https://www.murata.com/products/productdetail?partno=GRM155R61H104KE14%23"
			(at 165.1 10.16 0)
			(effects
				(font
					(size 1.27 1.27)
					(thickness 0.15)
				)
				(justify left bottom)
				(hide yes)
			)
		)
		(property "Description" ""
			(at 149.86 30.48 0)
			(effects
				(font
					(size 1.27 1.27)
				)
				(hide yes)
			)
		)
		(property "MPN" "GRM155R61H104KE14D"
			(at 167.64 10.16 0)
			(effects
				(font
					(size 1.27 1.27)
					(thickness 0.15)
				)
				(justify left bottom)
				(hide yes)
			)
		)
		(property "Manufacturer" "Murata"
			(at 170.18 10.16 0)
			(effects
				(font
					(size 1.27 1.27)
					(thickness 0.15)
				)
				(justify left bottom)
				(hide yes)
			)
		)
		(property "License" "Apache-2.0"
			(at 172.72 10.16 0)
			(effects
				(font
					(size 1.27 1.27)
					(thickness 0.15)
				)
				(justify left bottom)
				(hide yes)
			)
		)
		(property "Author" "Antmicro"
			(at 175.26 10.16 0)
			(effects
				(font
					(size 1.27 1.27)
					(thickness 0.15)
				)
				(justify left bottom)
				(hide yes)
			)
		)
		(property "Val" "100n"
			(at 152.4 29.2036 90)
			(effects
				(font
					(size 1.27 1.27)
					(thickness 0.15)
				)
				(justify right)
			)
		)
		(property "Voltage" "50V"
			(at 177.8 10.16 0)
			(effects
				(font
					(size 1.27 1.27)
				)
				(justify left bottom)
				(hide yes)
			)
		)
		(property "Dielectric" "X5R"
			(at 180.34 10.16 0)
			(effects
				(font
					(size 1.27 1.27)
				)
				(justify left bottom)
				(hide yes)
			)
		)
		(property "Public" "False"
			(at 182.88 10.16 0)
			(effects
				(font
					(size 1.27 1.27)
				)
				(justify left bottom)
				(hide yes)
			)
		)
		(pin "1"
		)
		(pin "2"
		)
		(instances
			(project "com-express-7-baseboard"
				(path ""
					(reference "C115")
					(unit 1)
				)
			)
		)
	)
	(symbol
		(lib_id "antmicropower:GND")
		(at 161.29 167.64 0)
		(unit 1)
		(exclude_from_sim no)
		(in_bom yes)
		(on_board yes)
		(dnp no)
		(property "Reference" "#PWR0304"
			(at 170.18 170.18 0)
			(effects
				(font
					(size 1.27 1.27)
					(thickness 0.15)
				)
				(justify left bottom)
				(hide yes)
			)
		)
		(property "Value" "GND"
			(at 161.29 171.45 0)
			(effects
				(font
					(size 1.27 1.27)
					(thickness 0.15)
				)
			)
		)
		(property "Footprint" ""
			(at 170.18 175.26 0)
			(effects
				(font
					(size 1.27 1.27)
					(thickness 0.15)
				)
				(justify left bottom)
				(hide yes)
			)
		)
		(property "Datasheet" ""
			(at 170.18 180.34 0)
			(effects
				(font
					(size 1.27 1.27)
					(thickness 0.15)
				)
				(justify left bottom)
				(hide yes)
			)
		)
		(property "Description" ""
			(at 161.29 167.64 0)
			(effects
				(font
					(size 1.27 1.27)
				)
				(hide yes)
			)
		)
		(property "Author" "Antmicro"
			(at 170.18 175.26 0)
			(effects
				(font
					(size 1.27 1.27)
					(thickness 0.15)
				)
				(justify left bottom)
				(hide yes)
			)
		)
		(property "License" "Apache-2.0"
			(at 170.18 177.8 0)
			(effects
				(font
					(size 1.27 1.27)
					(thickness 0.15)
				)
				(justify left bottom)
				(hide yes)
			)
		)
		(pin "1"
		)
		(instances
			(project "com-express-7-baseboard"
				(path ""
					(reference "#PWR0304")
					(unit 1)
				)
			)
		)
	)
	(symbol
		(lib_id "antmicroCapacitors0402:C_100n_0402")
		(at 167.64 45.72 90)
		(unit 1)
		(exclude_from_sim no)
		(in_bom yes)
		(on_board yes)
		(dnp no)
		(fields_autoplaced yes)
		(property "Reference" "C128"
			(at 170.18 41.9036 90)
			(effects
				(font
					(size 1.27 1.27)
					(thickness 0.15)
				)
				(justify right)
			)
		)
		(property "Value" "C_100n_0402"
			(at 177.8 25.4 0)
			(effects
				(font
					(size 1.27 1.27)
					(thickness 0.15)
				)
				(justify left bottom)
				(hide yes)
			)
		)
		(property "Footprint" "antmicro-footprints:C_0402_1005Metric"
			(at 180.34 25.4 0)
			(effects
				(font
					(size 1.27 1.27)
					(thickness 0.15)
				)
				(justify left bottom)
				(hide yes)
			)
		)
		(property "Datasheet" "https://www.murata.com/products/productdetail?partno=GRM155R61H104KE14%23"
			(at 182.88 25.4 0)
			(effects
				(font
					(size 1.27 1.27)
					(thickness 0.15)
				)
				(justify left bottom)
				(hide yes)
			)
		)
		(property "Description" ""
			(at 167.64 45.72 0)
			(effects
				(font
					(size 1.27 1.27)
				)
				(hide yes)
			)
		)
		(property "MPN" "GRM155R61H104KE14D"
			(at 185.42 25.4 0)
			(effects
				(font
					(size 1.27 1.27)
					(thickness 0.15)
				)
				(justify left bottom)
				(hide yes)
			)
		)
		(property "Manufacturer" "Murata"
			(at 187.96 25.4 0)
			(effects
				(font
					(size 1.27 1.27)
					(thickness 0.15)
				)
				(justify left bottom)
				(hide yes)
			)
		)
		(property "License" "Apache-2.0"
			(at 190.5 25.4 0)
			(effects
				(font
					(size 1.27 1.27)
					(thickness 0.15)
				)
				(justify left bottom)
				(hide yes)
			)
		)
		(property "Author" "Antmicro"
			(at 193.04 25.4 0)
			(effects
				(font
					(size 1.27 1.27)
					(thickness 0.15)
				)
				(justify left bottom)
				(hide yes)
			)
		)
		(property "Val" "100n"
			(at 170.18 44.4436 90)
			(effects
				(font
					(size 1.27 1.27)
					(thickness 0.15)
				)
				(justify right)
			)
		)
		(property "Voltage" "50V"
			(at 195.58 25.4 0)
			(effects
				(font
					(size 1.27 1.27)
				)
				(justify left bottom)
				(hide yes)
			)
		)
		(property "Dielectric" "X5R"
			(at 198.12 25.4 0)
			(effects
				(font
					(size 1.27 1.27)
				)
				(justify left bottom)
				(hide yes)
			)
		)
		(property "Public" "False"
			(at 200.66 25.4 0)
			(effects
				(font
					(size 1.27 1.27)
				)
				(justify left bottom)
				(hide yes)
			)
		)
		(pin "1"
		)
		(pin "2"
		)
		(instances
			(project "com-express-7-baseboard"
				(path ""
					(reference "C128")
					(unit 1)
				)
			)
		)
	)
	(symbol
		(lib_id "antmicroTestPoints:TP_0.75mm_SMD")
		(at 210.82 214.63 0)
		(unit 1)
		(exclude_from_sim no)
		(in_bom no)
		(on_board yes)
		(dnp no)
		(property "Reference" "TP53"
			(at 217.17 214.63 0)
			(effects
				(font
					(size 1.27 1.27)
					(thickness 0.15)
				)
			)
		)
		(property "Value" "TP_0.75mm_SMD"
			(at 221.615 218.44 0)
			(effects
				(font
					(size 1.27 1.27)
					(thickness 0.15)
				)
				(justify left bottom)
				(hide yes)
			)
		)
		(property "Footprint" "antmicro-footprints:TP_SMD_0.75mm"
			(at 221.615 220.98 0)
			(effects
				(font
					(size 1.27 1.27)
					(thickness 0.15)
				)
				(justify left bottom)
				(hide yes)
			)
		)
		(property "Datasheet" ""
			(at 228.6 227.33 0)
			(effects
				(font
					(size 1.27 1.27)
					(thickness 0.15)
				)
				(justify left bottom)
				(hide yes)
			)
		)
		(property "Description" ""
			(at 210.82 214.63 0)
			(effects
				(font
					(size 1.27 1.27)
				)
				(hide yes)
			)
		)
		(property "MPN" ""
			(at 221.615 226.06 0)
			(effects
				(font
					(size 1.27 1.27)
					(thickness 0.15)
				)
				(justify left bottom)
				(hide yes)
			)
		)
		(property "Manufacturer" ""
			(at 221.615 220.98 0)
			(effects
				(font
					(size 1.27 1.27)
					(thickness 0.15)
				)
				(justify left bottom)
				(hide yes)
			)
		)
		(property "Author" "Antmicro"
			(at 221.615 223.52 0)
			(effects
				(font
					(size 1.27 1.27)
					(thickness 0.15)
				)
				(justify left bottom)
				(hide yes)
			)
		)
		(property "License" "Apache-2.0"
			(at 221.615 226.06 0)
			(effects
				(font
					(size 1.27 1.27)
					(thickness 0.15)
				)
				(justify left bottom)
				(hide yes)
			)
		)
		(property "Public" "False"
			(at 220.98 228.6 0)
			(effects
				(font
					(size 1.27 1.27)
				)
				(justify left bottom)
				(hide yes)
			)
		)
		(pin "1"
		)
		(instances
			(project "com-express-7-baseboard"
				(path ""
					(reference "TP53")
					(unit 1)
				)
			)
		)
	)
	(symbol
		(lib_id "antmicropower:GND")
		(at 158.75 45.72 0)
		(unit 1)
		(exclude_from_sim no)
		(in_bom yes)
		(on_board yes)
		(dnp no)
		(property "Reference" "#PWR0302"
			(at 167.64 48.26 0)
			(effects
				(font
					(size 1.27 1.27)
					(thickness 0.15)
				)
				(justify left bottom)
				(hide yes)
			)
		)
		(property "Value" "GND"
			(at 158.75 49.53 0)
			(effects
				(font
					(size 1.27 1.27)
					(thickness 0.15)
				)
			)
		)
		(property "Footprint" ""
			(at 167.64 53.34 0)
			(effects
				(font
					(size 1.27 1.27)
					(thickness 0.15)
				)
				(justify left bottom)
				(hide yes)
			)
		)
		(property "Datasheet" ""
			(at 167.64 58.42 0)
			(effects
				(font
					(size 1.27 1.27)
					(thickness 0.15)
				)
				(justify left bottom)
				(hide yes)
			)
		)
		(property "Description" ""
			(at 158.75 45.72 0)
			(effects
				(font
					(size 1.27 1.27)
				)
				(hide yes)
			)
		)
		(property "Author" "Antmicro"
			(at 167.64 53.34 0)
			(effects
				(font
					(size 1.27 1.27)
					(thickness 0.15)
				)
				(justify left bottom)
				(hide yes)
			)
		)
		(property "License" "Apache-2.0"
			(at 167.64 55.88 0)
			(effects
				(font
					(size 1.27 1.27)
					(thickness 0.15)
				)
				(justify left bottom)
				(hide yes)
			)
		)
		(pin "1"
		)
		(instances
			(project "com-express-7-baseboard"
				(path ""
					(reference "#PWR0302")
					(unit 1)
				)
			)
		)
	)
	(symbol
		(lib_id "antmicroResistors0402:R_1k_0402")
		(at 151.13 127 90)
		(unit 1)
		(exclude_from_sim no)
		(in_bom yes)
		(on_board yes)
		(dnp yes)
		(property "Reference" "R207"
			(at 151.13 130.81 0)
			(effects
				(font
					(size 1.27 1.27)
					(thickness 0.15)
				)
				(justify right)
			)
		)
		(property "Value" "R_1k_0402"
			(at 163.83 106.68 0)
			(effects
				(font
					(size 1.27 1.27)
					(thickness 0.15)
				)
				(justify left bottom)
				(hide yes)
			)
		)
		(property "Footprint" "antmicro-footprints:R_0402_1005Metric"
			(at 166.37 106.68 0)
			(effects
				(font
					(size 1.27 1.27)
					(thickness 0.15)
				)
				(justify left bottom)
				(hide yes)
			)
		)
		(property "Datasheet" "https://www.bourns.com/docs/product-datasheets/cr.pdf"
			(at 168.91 106.68 0)
			(effects
				(font
					(size 1.27 1.27)
					(thickness 0.15)
				)
				(justify left bottom)
				(hide yes)
			)
		)
		(property "Description" ""
			(at 151.13 127 0)
			(effects
				(font
					(size 1.27 1.27)
				)
				(hide yes)
			)
		)
		(property "MPN" "CR0402-FX-1001GLF"
			(at 171.45 106.68 0)
			(effects
				(font
					(size 1.27 1.27)
					(thickness 0.15)
				)
				(justify left bottom)
				(hide yes)
			)
		)
		(property "Manufacturer" "Bourns"
			(at 173.99 106.68 0)
			(effects
				(font
					(size 1.27 1.27)
					(thickness 0.15)
				)
				(justify left bottom)
				(hide yes)
			)
		)
		(property "License" "Apache-2.0"
			(at 176.53 106.68 0)
			(effects
				(font
					(size 1.27 1.27)
					(thickness 0.15)
				)
				(justify left bottom)
				(hide yes)
			)
		)
		(property "Author" "Antmicro"
			(at 179.07 106.68 0)
			(effects
				(font
					(size 1.27 1.27)
					(thickness 0.15)
				)
				(justify left bottom)
				(hide yes)
			)
		)
		(property "Val" "1k"
			(at 149.86 127 0)
			(effects
				(font
					(size 1.27 1.27)
					(thickness 0.15)
				)
				(justify right)
			)
		)
		(property "Tolerance" "1%"
			(at 161.29 106.68 0)
			(effects
				(font
					(size 1.27 1.27)
				)
				(justify left bottom)
				(hide yes)
			)
		)
		(property "Public" "False"
			(at 181.61 106.68 0)
			(effects
				(font
					(size 1.27 1.27)
				)
				(justify left bottom)
				(hide yes)
			)
		)
		(pin "1"
		)
		(pin "2"
		)
		(instances
			(project "com-express-7-baseboard"
				(path ""
					(reference "R207")
					(unit 1)
				)
			)
		)
	)
	(symbol
		(lib_id "antmicroResistors0402:R_1k_0402")
		(at 148.59 97.79 270)
		(unit 1)
		(exclude_from_sim no)
		(in_bom yes)
		(on_board yes)
		(dnp yes)
		(property "Reference" "R204"
			(at 148.59 93.98 0)
			(effects
				(font
					(size 1.27 1.27)
					(thickness 0.15)
				)
				(justify right)
			)
		)
		(property "Value" "R_1k_0402"
			(at 135.89 118.11 0)
			(effects
				(font
					(size 1.27 1.27)
					(thickness 0.15)
				)
				(justify left bottom)
				(hide yes)
			)
		)
		(property "Footprint" "antmicro-footprints:R_0402_1005Metric"
			(at 133.35 118.11 0)
			(effects
				(font
					(size 1.27 1.27)
					(thickness 0.15)
				)
				(justify left bottom)
				(hide yes)
			)
		)
		(property "Datasheet" "https://www.bourns.com/docs/product-datasheets/cr.pdf"
			(at 130.81 118.11 0)
			(effects
				(font
					(size 1.27 1.27)
					(thickness 0.15)
				)
				(justify left bottom)
				(hide yes)
			)
		)
		(property "Description" ""
			(at 148.59 97.79 0)
			(effects
				(font
					(size 1.27 1.27)
				)
				(hide yes)
			)
		)
		(property "MPN" "CR0402-FX-1001GLF"
			(at 128.27 118.11 0)
			(effects
				(font
					(size 1.27 1.27)
					(thickness 0.15)
				)
				(justify left bottom)
				(hide yes)
			)
		)
		(property "Manufacturer" "Bourns"
			(at 125.73 118.11 0)
			(effects
				(font
					(size 1.27 1.27)
					(thickness 0.15)
				)
				(justify left bottom)
				(hide yes)
			)
		)
		(property "License" "Apache-2.0"
			(at 123.19 118.11 0)
			(effects
				(font
					(size 1.27 1.27)
					(thickness 0.15)
				)
				(justify left bottom)
				(hide yes)
			)
		)
		(property "Author" "Antmicro"
			(at 120.65 118.11 0)
			(effects
				(font
					(size 1.27 1.27)
					(thickness 0.15)
				)
				(justify left bottom)
				(hide yes)
			)
		)
		(property "Val" "1k"
			(at 149.86 97.79 0)
			(effects
				(font
					(size 1.27 1.27)
					(thickness 0.15)
				)
				(justify right)
			)
		)
		(property "Tolerance" "1%"
			(at 138.43 118.11 0)
			(effects
				(font
					(size 1.27 1.27)
				)
				(justify left bottom)
				(hide yes)
			)
		)
		(property "Public" "False"
			(at 118.11 118.11 0)
			(effects
				(font
					(size 1.27 1.27)
				)
				(justify left bottom)
				(hide yes)
			)
		)
		(pin "1"
		)
		(pin "2"
		)
		(instances
			(project "com-express-7-baseboard"
				(path ""
					(reference "R204")
					(unit 1)
				)
			)
		)
	)
	(symbol
		(lib_id "antmicroResistors0402:R_1k_0402")
		(at 242.57 222.25 90)
		(mirror x)
		(unit 1)
		(exclude_from_sim no)
		(in_bom yes)
		(on_board yes)
		(dnp no)
		(property "Reference" "R225"
			(at 242.57 218.44 0)
			(effects
				(font
					(size 1.27 1.27)
					(thickness 0.15)
				)
				(justify right)
			)
		)
		(property "Value" "R_1k_0402"
			(at 255.27 242.57 0)
			(effects
				(font
					(size 1.27 1.27)
					(thickness 0.15)
				)
				(justify left bottom)
				(hide yes)
			)
		)
		(property "Footprint" "antmicro-footprints:R_0402_1005Metric"
			(at 257.81 242.57 0)
			(effects
				(font
					(size 1.27 1.27)
					(thickness 0.15)
				)
				(justify left bottom)
				(hide yes)
			)
		)
		(property "Datasheet" "https://www.bourns.com/docs/product-datasheets/cr.pdf"
			(at 260.35 242.57 0)
			(effects
				(font
					(size 1.27 1.27)
					(thickness 0.15)
				)
				(justify left bottom)
				(hide yes)
			)
		)
		(property "Description" ""
			(at 242.57 222.25 0)
			(effects
				(font
					(size 1.27 1.27)
				)
				(hide yes)
			)
		)
		(property "MPN" "CR0402-FX-1001GLF"
			(at 262.89 242.57 0)
			(effects
				(font
					(size 1.27 1.27)
					(thickness 0.15)
				)
				(justify left bottom)
				(hide yes)
			)
		)
		(property "Manufacturer" "Bourns"
			(at 265.43 242.57 0)
			(effects
				(font
					(size 1.27 1.27)
					(thickness 0.15)
				)
				(justify left bottom)
				(hide yes)
			)
		)
		(property "License" "Apache-2.0"
			(at 267.97 242.57 0)
			(effects
				(font
					(size 1.27 1.27)
					(thickness 0.15)
				)
				(justify left bottom)
				(hide yes)
			)
		)
		(property "Author" "Antmicro"
			(at 270.51 242.57 0)
			(effects
				(font
					(size 1.27 1.27)
					(thickness 0.15)
				)
				(justify left bottom)
				(hide yes)
			)
		)
		(property "Val" "1k"
			(at 241.3 222.25 0)
			(effects
				(font
					(size 1.27 1.27)
					(thickness 0.15)
				)
				(justify right)
			)
		)
		(property "Tolerance" "1%"
			(at 252.73 242.57 0)
			(effects
				(font
					(size 1.27 1.27)
				)
				(justify left bottom)
				(hide yes)
			)
		)
		(property "Public" "False"
			(at 273.05 242.57 0)
			(effects
				(font
					(size 1.27 1.27)
				)
				(justify left bottom)
				(hide yes)
			)
		)
		(pin "1"
		)
		(pin "2"
		)
		(instances
			(project "com-express-7-baseboard"
				(path ""
					(reference "R225")
					(unit 1)
				)
			)
		)
	)
	(symbol
		(lib_id "antmicroResistors0402:R_1k_0402")
		(at 234.95 222.25 90)
		(mirror x)
		(unit 1)
		(exclude_from_sim no)
		(in_bom yes)
		(on_board yes)
		(dnp no)
		(property "Reference" "R219"
			(at 234.95 218.44 0)
			(effects
				(font
					(size 1.27 1.27)
					(thickness 0.15)
				)
				(justify right)
			)
		)
		(property "Value" "R_1k_0402"
			(at 247.65 242.57 0)
			(effects
				(font
					(size 1.27 1.27)
					(thickness 0.15)
				)
				(justify left bottom)
				(hide yes)
			)
		)
		(property "Footprint" "antmicro-footprints:R_0402_1005Metric"
			(at 250.19 242.57 0)
			(effects
				(font
					(size 1.27 1.27)
					(thickness 0.15)
				)
				(justify left bottom)
				(hide yes)
			)
		)
		(property "Datasheet" "https://www.bourns.com/docs/product-datasheets/cr.pdf"
			(at 252.73 242.57 0)
			(effects
				(font
					(size 1.27 1.27)
					(thickness 0.15)
				)
				(justify left bottom)
				(hide yes)
			)
		)
		(property "Description" ""
			(at 234.95 222.25 0)
			(effects
				(font
					(size 1.27 1.27)
				)
				(hide yes)
			)
		)
		(property "MPN" "CR0402-FX-1001GLF"
			(at 255.27 242.57 0)
			(effects
				(font
					(size 1.27 1.27)
					(thickness 0.15)
				)
				(justify left bottom)
				(hide yes)
			)
		)
		(property "Manufacturer" "Bourns"
			(at 257.81 242.57 0)
			(effects
				(font
					(size 1.27 1.27)
					(thickness 0.15)
				)
				(justify left bottom)
				(hide yes)
			)
		)
		(property "License" "Apache-2.0"
			(at 260.35 242.57 0)
			(effects
				(font
					(size 1.27 1.27)
					(thickness 0.15)
				)
				(justify left bottom)
				(hide yes)
			)
		)
		(property "Author" "Antmicro"
			(at 262.89 242.57 0)
			(effects
				(font
					(size 1.27 1.27)
					(thickness 0.15)
				)
				(justify left bottom)
				(hide yes)
			)
		)
		(property "Val" "1k"
			(at 233.68 222.25 0)
			(effects
				(font
					(size 1.27 1.27)
					(thickness 0.15)
				)
				(justify right)
			)
		)
		(property "Tolerance" "1%"
			(at 245.11 242.57 0)
			(effects
				(font
					(size 1.27 1.27)
				)
				(justify left bottom)
				(hide yes)
			)
		)
		(property "Public" "False"
			(at 265.43 242.57 0)
			(effects
				(font
					(size 1.27 1.27)
				)
				(justify left bottom)
				(hide yes)
			)
		)
		(pin "1"
		)
		(pin "2"
		)
		(instances
			(project "com-express-7-baseboard"
				(path ""
					(reference "R219")
					(unit 1)
				)
			)
		)
	)
	(symbol
		(lib_id "antmicropower:GND")
		(at 167.64 30.48 0)
		(unit 1)
		(exclude_from_sim no)
		(in_bom yes)
		(on_board yes)
		(dnp no)
		(property "Reference" "#PWR0306"
			(at 176.53 33.02 0)
			(effects
				(font
					(size 1.27 1.27)
					(thickness 0.15)
				)
				(justify left bottom)
				(hide yes)
			)
		)
		(property "Value" "GND"
			(at 167.64 34.29 0)
			(effects
				(font
					(size 1.27 1.27)
					(thickness 0.15)
				)
			)
		)
		(property "Footprint" ""
			(at 176.53 38.1 0)
			(effects
				(font
					(size 1.27 1.27)
					(thickness 0.15)
				)
				(justify left bottom)
				(hide yes)
			)
		)
		(property "Datasheet" ""
			(at 176.53 43.18 0)
			(effects
				(font
					(size 1.27 1.27)
					(thickness 0.15)
				)
				(justify left bottom)
				(hide yes)
			)
		)
		(property "Description" ""
			(at 167.64 30.48 0)
			(effects
				(font
					(size 1.27 1.27)
				)
				(hide yes)
			)
		)
		(property "Author" "Antmicro"
			(at 176.53 38.1 0)
			(effects
				(font
					(size 1.27 1.27)
					(thickness 0.15)
				)
				(justify left bottom)
				(hide yes)
			)
		)
		(property "License" "Apache-2.0"
			(at 176.53 40.64 0)
			(effects
				(font
					(size 1.27 1.27)
					(thickness 0.15)
				)
				(justify left bottom)
				(hide yes)
			)
		)
		(pin "1"
		)
		(instances
			(project "com-express-7-baseboard"
				(path ""
					(reference "#PWR0306")
					(unit 1)
				)
			)
		)
	)
	(symbol
		(lib_id "antmicroResistors0402:R_1k_0402")
		(at 234.95 251.46 270)
		(mirror x)
		(unit 1)
		(exclude_from_sim no)
		(in_bom yes)
		(on_board yes)
		(dnp yes)
		(property "Reference" "R220"
			(at 234.95 255.27 0)
			(effects
				(font
					(size 1.27 1.27)
					(thickness 0.15)
				)
				(justify right)
			)
		)
		(property "Value" "R_1k_0402"
			(at 222.25 231.14 0)
			(effects
				(font
					(size 1.27 1.27)
					(thickness 0.15)
				)
				(justify left bottom)
				(hide yes)
			)
		)
		(property "Footprint" "antmicro-footprints:R_0402_1005Metric"
			(at 219.71 231.14 0)
			(effects
				(font
					(size 1.27 1.27)
					(thickness 0.15)
				)
				(justify left bottom)
				(hide yes)
			)
		)
		(property "Datasheet" "https://www.bourns.com/docs/product-datasheets/cr.pdf"
			(at 217.17 231.14 0)
			(effects
				(font
					(size 1.27 1.27)
					(thickness 0.15)
				)
				(justify left bottom)
				(hide yes)
			)
		)
		(property "Description" ""
			(at 234.95 251.46 0)
			(effects
				(font
					(size 1.27 1.27)
				)
				(hide yes)
			)
		)
		(property "MPN" "CR0402-FX-1001GLF"
			(at 214.63 231.14 0)
			(effects
				(font
					(size 1.27 1.27)
					(thickness 0.15)
				)
				(justify left bottom)
				(hide yes)
			)
		)
		(property "Manufacturer" "Bourns"
			(at 212.09 231.14 0)
			(effects
				(font
					(size 1.27 1.27)
					(thickness 0.15)
				)
				(justify left bottom)
				(hide yes)
			)
		)
		(property "License" "Apache-2.0"
			(at 209.55 231.14 0)
			(effects
				(font
					(size 1.27 1.27)
					(thickness 0.15)
				)
				(justify left bottom)
				(hide yes)
			)
		)
		(property "Author" "Antmicro"
			(at 207.01 231.14 0)
			(effects
				(font
					(size 1.27 1.27)
					(thickness 0.15)
				)
				(justify left bottom)
				(hide yes)
			)
		)
		(property "Val" "1k"
			(at 236.22 251.46 0)
			(effects
				(font
					(size 1.27 1.27)
					(thickness 0.15)
				)
				(justify right)
			)
		)
		(property "Tolerance" "1%"
			(at 224.79 231.14 0)
			(effects
				(font
					(size 1.27 1.27)
				)
				(justify left bottom)
				(hide yes)
			)
		)
		(property "Public" "False"
			(at 204.47 231.14 0)
			(effects
				(font
					(size 1.27 1.27)
				)
				(justify left bottom)
				(hide yes)
			)
		)
		(pin "1"
		)
		(pin "2"
		)
		(instances
			(project "com-express-7-baseboard"
				(path ""
					(reference "R220")
					(unit 1)
				)
			)
		)
	)
	(symbol
		(lib_id "antmicroResistors0402:R_1k_0402")
		(at 245.11 251.46 270)
		(mirror x)
		(unit 1)
		(exclude_from_sim no)
		(in_bom yes)
		(on_board yes)
		(dnp no)
		(property "Reference" "R228"
			(at 245.11 255.27 0)
			(effects
				(font
					(size 1.27 1.27)
					(thickness 0.15)
				)
				(justify right)
			)
		)
		(property "Value" "R_1k_0402"
			(at 232.41 231.14 0)
			(effects
				(font
					(size 1.27 1.27)
					(thickness 0.15)
				)
				(justify left bottom)
				(hide yes)
			)
		)
		(property "Footprint" "antmicro-footprints:R_0402_1005Metric"
			(at 229.87 231.14 0)
			(effects
				(font
					(size 1.27 1.27)
					(thickness 0.15)
				)
				(justify left bottom)
				(hide yes)
			)
		)
		(property "Datasheet" "https://www.bourns.com/docs/product-datasheets/cr.pdf"
			(at 227.33 231.14 0)
			(effects
				(font
					(size 1.27 1.27)
					(thickness 0.15)
				)
				(justify left bottom)
				(hide yes)
			)
		)
		(property "Description" ""
			(at 245.11 251.46 0)
			(effects
				(font
					(size 1.27 1.27)
				)
				(hide yes)
			)
		)
		(property "MPN" "CR0402-FX-1001GLF"
			(at 224.79 231.14 0)
			(effects
				(font
					(size 1.27 1.27)
					(thickness 0.15)
				)
				(justify left bottom)
				(hide yes)
			)
		)
		(property "Manufacturer" "Bourns"
			(at 222.25 231.14 0)
			(effects
				(font
					(size 1.27 1.27)
					(thickness 0.15)
				)
				(justify left bottom)
				(hide yes)
			)
		)
		(property "License" "Apache-2.0"
			(at 219.71 231.14 0)
			(effects
				(font
					(size 1.27 1.27)
					(thickness 0.15)
				)
				(justify left bottom)
				(hide yes)
			)
		)
		(property "Author" "Antmicro"
			(at 217.17 231.14 0)
			(effects
				(font
					(size 1.27 1.27)
					(thickness 0.15)
				)
				(justify left bottom)
				(hide yes)
			)
		)
		(property "Val" "1k"
			(at 246.38 251.46 0)
			(effects
				(font
					(size 1.27 1.27)
					(thickness 0.15)
				)
				(justify right)
			)
		)
		(property "Tolerance" "1%"
			(at 234.95 231.14 0)
			(effects
				(font
					(size 1.27 1.27)
				)
				(justify left bottom)
				(hide yes)
			)
		)
		(property "Public" "False"
			(at 214.63 231.14 0)
			(effects
				(font
					(size 1.27 1.27)
				)
				(justify left bottom)
				(hide yes)
			)
		)
		(pin "1"
		)
		(pin "2"
		)
		(instances
			(project "com-express-7-baseboard"
				(path ""
					(reference "R228")
					(unit 1)
				)
			)
		)
	)
	(symbol
		(lib_id "antmicroInterfaceDriversReceiversTransceivers:PI3EQX16904GL")
		(at 208.28 179.07 0)
		(mirror y)
		(unit 1)
		(exclude_from_sim no)
		(in_bom yes)
		(on_board yes)
		(dnp no)
		(fields_autoplaced yes)
		(property "Reference" "U40"
			(at 196.85 171.45 0)
			(effects
				(font
					(size 1.27 1.27)
					(thickness 0.15)
				)
			)
		)
		(property "Value" "PI3EQX16904GL"
			(at 172.72 189.23 0)
			(effects
				(font
					(size 1.27 1.27)
					(thickness 0.15)
				)
				(justify left bottom)
				(hide yes)
			)
		)
		(property "Footprint" "antmicro-footprints:WQFN-42-1EP_3.5x9mm_P0.5mm"
			(at 172.72 191.77 0)
			(effects
				(font
					(size 1.27 1.27)
					(thickness 0.15)
				)
				(justify left bottom)
				(hide yes)
			)
		)
		(property "Datasheet" "https://www.diodes.com/part/view/PI3EQX16904GL"
			(at 172.72 194.31 0)
			(effects
				(font
					(size 1.27 1.27)
					(thickness 0.15)
				)
				(justify left bottom)
				(hide yes)
			)
		)
		(property "Description" ""
			(at 208.28 179.07 0)
			(effects
				(font
					(size 1.27 1.27)
				)
				(hide yes)
			)
		)
		(property "MPN" "PI3EQX16904GLZHEX"
			(at 196.85 173.99 0)
			(effects
				(font
					(size 1.27 1.27)
					(thickness 0.15)
				)
			)
		)
		(property "Manufacturer" "Diodes Incorporated"
			(at 172.72 186.69 0)
			(effects
				(font
					(size 1.27 1.27)
					(thickness 0.15)
				)
				(justify left bottom)
				(hide yes)
			)
		)
		(property "Author" "Antmicro"
			(at 172.72 196.85 0)
			(effects
				(font
					(size 1.27 1.27)
					(thickness 0.15)
				)
				(justify left bottom)
				(hide yes)
			)
		)
		(property "License" "Apache-2.0"
			(at 172.72 199.39 0)
			(effects
				(font
					(size 1.27 1.27)
					(thickness 0.15)
				)
				(justify left bottom)
				(hide yes)
			)
		)
		(pin "9"
		)
		(pin "29"
		)
		(pin "30"
		)
		(pin "4"
		)
		(pin "20"
		)
		(pin "33"
		)
		(pin "3"
		)
		(pin "19"
		)
		(pin "25"
		)
		(pin "34"
		)
		(pin "31"
		)
		(pin "23"
		)
		(pin "26"
		)
		(pin "27"
		)
		(pin "42"
		)
		(pin "41"
		)
		(pin "24"
		)
		(pin "2"
		)
		(pin "39"
		)
		(pin "28"
		)
		(pin "7"
		)
		(pin "36"
		)
		(pin "43"
		)
		(pin "38"
		)
		(pin "8"
		)
		(pin "5"
		)
		(pin "6"
		)
		(pin "37"
		)
		(pin "40"
		)
		(pin "35"
		)
		(pin "18"
		)
		(pin "21"
		)
		(pin "17"
		)
		(pin "10"
		)
		(pin "1"
		)
		(pin "16"
		)
		(pin "15"
		)
		(pin "14"
		)
		(pin "13"
		)
		(pin "12"
		)
		(pin "11"
		)
		(pin "32"
		)
		(pin "22"
		)
		(instances
			(project "com-express-7-baseboard"
				(path ""
					(reference "U40")
					(unit 1)
				)
			)
		)
	)
	(symbol
		(lib_id "antmicropower:+3V3")
		(at 152.4 143.51 0)
		(unit 1)
		(exclude_from_sim no)
		(in_bom yes)
		(on_board yes)
		(dnp no)
		(fields_autoplaced yes)
		(property "Reference" "#PWR0298"
			(at 167.64 143.51 0)
			(effects
				(font
					(size 1.27 1.27)
					(thickness 0.15)
				)
				(justify left bottom)
				(hide yes)
			)
		)
		(property "Value" "+3V3"
			(at 152.4 138.43 0)
			(effects
				(font
					(size 1.27 1.27)
					(thickness 0.15)
				)
			)
		)
		(property "Footprint" ""
			(at 167.64 151.13 0)
			(effects
				(font
					(size 1.27 1.27)
					(thickness 0.15)
				)
				(justify left bottom)
				(hide yes)
			)
		)
		(property "Datasheet" ""
			(at 167.64 153.67 0)
			(effects
				(font
					(size 1.27 1.27)
					(thickness 0.15)
				)
				(justify left bottom)
				(hide yes)
			)
		)
		(property "Description" ""
			(at 152.4 143.51 0)
			(effects
				(font
					(size 1.27 1.27)
				)
				(hide yes)
			)
		)
		(property "Author" "Antmicro"
			(at 167.64 146.05 0)
			(effects
				(font
					(size 1.27 1.27)
					(thickness 0.15)
				)
				(justify left bottom)
				(hide yes)
			)
		)
		(property "License" "Apache-2.0"
			(at 167.64 148.59 0)
			(effects
				(font
					(size 1.27 1.27)
					(thickness 0.15)
				)
				(justify left bottom)
				(hide yes)
			)
		)
		(pin "1"
		)
		(instances
			(project "com-express-7-baseboard"
				(path ""
					(reference "#PWR0298")
					(unit 1)
				)
			)
		)
	)
	(symbol
		(lib_id "antmicroCapacitors0402:C_220n_0402")
		(at 154.94 184.15 0)
		(unit 1)
		(exclude_from_sim no)
		(in_bom yes)
		(on_board yes)
		(dnp no)
		(property "Reference" "C129"
			(at 153.67 182.88 0)
			(effects
				(font
					(size 1.27 1.27)
					(thickness 0.15)
				)
			)
		)
		(property "Value" "C_220n_0402"
			(at 175.26 194.31 0)
			(effects
				(font
					(size 1.27 1.27)
					(thickness 0.15)
				)
				(justify left bottom)
				(hide yes)
			)
		)
		(property "Footprint" "antmicro-footprints:C_0402_1005Metric"
			(at 175.26 196.85 0)
			(effects
				(font
					(size 1.27 1.27)
					(thickness 0.15)
				)
				(justify left bottom)
				(hide yes)
			)
		)
		(property "Datasheet" "https://www.yageo.com/en/Chart/Download/pdf/CC0402KRX5R6BB224"
			(at 175.26 199.39 0)
			(effects
				(font
					(size 1.27 1.27)
					(thickness 0.15)
				)
				(justify left bottom)
				(hide yes)
			)
		)
		(property "Description" ""
			(at 154.94 184.15 0)
			(effects
				(font
					(size 1.27 1.27)
				)
				(hide yes)
			)
		)
		(property "MPN" "CC0402KRX5R6BB224"
			(at 175.26 201.93 0)
			(effects
				(font
					(size 1.27 1.27)
					(thickness 0.15)
				)
				(justify left bottom)
				(hide yes)
			)
		)
		(property "Manufacturer" "YAGEO"
			(at 175.26 204.47 0)
			(effects
				(font
					(size 1.27 1.27)
					(thickness 0.15)
				)
				(justify left bottom)
				(hide yes)
			)
		)
		(property "License" "Apache-2.0"
			(at 175.26 207.01 0)
			(effects
				(font
					(size 1.27 1.27)
					(thickness 0.15)
				)
				(justify left bottom)
				(hide yes)
			)
		)
		(property "Author" "Antmicro"
			(at 175.26 209.55 0)
			(effects
				(font
					(size 1.27 1.27)
					(thickness 0.15)
				)
				(justify left bottom)
				(hide yes)
			)
		)
		(property "Val" "220n"
			(at 161.29 182.88 0)
			(effects
				(font
					(size 1.27 1.27)
					(thickness 0.15)
				)
			)
		)
		(property "Voltage" ""
			(at 175.26 212.09 0)
			(effects
				(font
					(size 1.27 1.27)
				)
				(justify left bottom)
				(hide yes)
			)
		)
		(property "Dielectric" ""
			(at 175.26 214.63 0)
			(effects
				(font
					(size 1.27 1.27)
				)
				(justify left bottom)
				(hide yes)
			)
		)
		(property "Public" "False"
			(at 175.26 217.17 0)
			(effects
				(font
					(size 1.27 1.27)
				)
				(justify left bottom)
				(hide yes)
			)
		)
		(pin "1"
		)
		(pin "2"
		)
		(instances
			(project "com-express-7-baseboard"
				(path ""
					(reference "C129")
					(unit 1)
				)
			)
		)
	)
	(symbol
		(lib_id "antmicropower:GND")
		(at 140.97 30.48 0)
		(unit 1)
		(exclude_from_sim no)
		(in_bom yes)
		(on_board yes)
		(dnp no)
		(property "Reference" "#PWR0292"
			(at 149.86 33.02 0)
			(effects
				(font
					(size 1.27 1.27)
					(thickness 0.15)
				)
				(justify left bottom)
				(hide yes)
			)
		)
		(property "Value" "GND"
			(at 140.97 34.29 0)
			(effects
				(font
					(size 1.27 1.27)
					(thickness 0.15)
				)
			)
		)
		(property "Footprint" ""
			(at 149.86 38.1 0)
			(effects
				(font
					(size 1.27 1.27)
					(thickness 0.15)
				)
				(justify left bottom)
				(hide yes)
			)
		)
		(property "Datasheet" ""
			(at 149.86 43.18 0)
			(effects
				(font
					(size 1.27 1.27)
					(thickness 0.15)
				)
				(justify left bottom)
				(hide yes)
			)
		)
		(property "Description" ""
			(at 140.97 30.48 0)
			(effects
				(font
					(size 1.27 1.27)
				)
				(hide yes)
			)
		)
		(property "Author" "Antmicro"
			(at 149.86 38.1 0)
			(effects
				(font
					(size 1.27 1.27)
					(thickness 0.15)
				)
				(justify left bottom)
				(hide yes)
			)
		)
		(property "License" "Apache-2.0"
			(at 149.86 40.64 0)
			(effects
				(font
					(size 1.27 1.27)
					(thickness 0.15)
				)
				(justify left bottom)
				(hide yes)
			)
		)
		(pin "1"
		)
		(instances
			(project "com-express-7-baseboard"
				(path ""
					(reference "#PWR0292")
					(unit 1)
				)
			)
		)
	)
	(symbol
		(lib_id "antmicropower:GND")
		(at 161.29 152.4 0)
		(unit 1)
		(exclude_from_sim no)
		(in_bom yes)
		(on_board yes)
		(dnp no)
		(property "Reference" "#PWR0303"
			(at 170.18 154.94 0)
			(effects
				(font
					(size 1.27 1.27)
					(thickness 0.15)
				)
				(justify left bottom)
				(hide yes)
			)
		)
		(property "Value" "GND"
			(at 161.29 156.21 0)
			(effects
				(font
					(size 1.27 1.27)
					(thickness 0.15)
				)
			)
		)
		(property "Footprint" ""
			(at 170.18 160.02 0)
			(effects
				(font
					(size 1.27 1.27)
					(thickness 0.15)
				)
				(justify left bottom)
				(hide yes)
			)
		)
		(property "Datasheet" ""
			(at 170.18 165.1 0)
			(effects
				(font
					(size 1.27 1.27)
					(thickness 0.15)
				)
				(justify left bottom)
				(hide yes)
			)
		)
		(property "Description" ""
			(at 161.29 152.4 0)
			(effects
				(font
					(size 1.27 1.27)
				)
				(hide yes)
			)
		)
		(property "Author" "Antmicro"
			(at 170.18 160.02 0)
			(effects
				(font
					(size 1.27 1.27)
					(thickness 0.15)
				)
				(justify left bottom)
				(hide yes)
			)
		)
		(property "License" "Apache-2.0"
			(at 170.18 162.56 0)
			(effects
				(font
					(size 1.27 1.27)
					(thickness 0.15)
				)
				(justify left bottom)
				(hide yes)
			)
		)
		(pin "1"
		)
		(instances
			(project "com-express-7-baseboard"
				(path ""
					(reference "#PWR0303")
					(unit 1)
				)
			)
		)
	)
	(symbol
		(lib_id "antmicroResistors0402:R_1k_0402")
		(at 242.57 251.46 270)
		(mirror x)
		(unit 1)
		(exclude_from_sim no)
		(in_bom yes)
		(on_board yes)
		(dnp yes)
		(property "Reference" "R226"
			(at 242.57 255.27 0)
			(effects
				(font
					(size 1.27 1.27)
					(thickness 0.15)
				)
				(justify right)
			)
		)
		(property "Value" "R_1k_0402"
			(at 229.87 231.14 0)
			(effects
				(font
					(size 1.27 1.27)
					(thickness 0.15)
				)
				(justify left bottom)
				(hide yes)
			)
		)
		(property "Footprint" "antmicro-footprints:R_0402_1005Metric"
			(at 227.33 231.14 0)
			(effects
				(font
					(size 1.27 1.27)
					(thickness 0.15)
				)
				(justify left bottom)
				(hide yes)
			)
		)
		(property "Datasheet" "https://www.bourns.com/docs/product-datasheets/cr.pdf"
			(at 224.79 231.14 0)
			(effects
				(font
					(size 1.27 1.27)
					(thickness 0.15)
				)
				(justify left bottom)
				(hide yes)
			)
		)
		(property "Description" ""
			(at 242.57 251.46 0)
			(effects
				(font
					(size 1.27 1.27)
				)
				(hide yes)
			)
		)
		(property "MPN" "CR0402-FX-1001GLF"
			(at 222.25 231.14 0)
			(effects
				(font
					(size 1.27 1.27)
					(thickness 0.15)
				)
				(justify left bottom)
				(hide yes)
			)
		)
		(property "Manufacturer" "Bourns"
			(at 219.71 231.14 0)
			(effects
				(font
					(size 1.27 1.27)
					(thickness 0.15)
				)
				(justify left bottom)
				(hide yes)
			)
		)
		(property "License" "Apache-2.0"
			(at 217.17 231.14 0)
			(effects
				(font
					(size 1.27 1.27)
					(thickness 0.15)
				)
				(justify left bottom)
				(hide yes)
			)
		)
		(property "Author" "Antmicro"
			(at 214.63 231.14 0)
			(effects
				(font
					(size 1.27 1.27)
					(thickness 0.15)
				)
				(justify left bottom)
				(hide yes)
			)
		)
		(property "Val" "1k"
			(at 243.84 251.46 0)
			(effects
				(font
					(size 1.27 1.27)
					(thickness 0.15)
				)
				(justify right)
			)
		)
		(property "Tolerance" "1%"
			(at 232.41 231.14 0)
			(effects
				(font
					(size 1.27 1.27)
				)
				(justify left bottom)
				(hide yes)
			)
		)
		(property "Public" "False"
			(at 212.09 231.14 0)
			(effects
				(font
					(size 1.27 1.27)
				)
				(justify left bottom)
				(hide yes)
			)
		)
		(pin "1"
		)
		(pin "2"
		)
		(instances
			(project "com-express-7-baseboard"
				(path ""
					(reference "R226")
					(unit 1)
				)
			)
		)
	)
	(symbol
		(lib_id "antmicroResistors0402:R_1k_0402")
		(at 245.11 222.25 90)
		(mirror x)
		(unit 1)
		(exclude_from_sim no)
		(in_bom yes)
		(on_board yes)
		(dnp yes)
		(property "Reference" "R227"
			(at 245.11 218.44 0)
			(effects
				(font
					(size 1.27 1.27)
					(thickness 0.15)
				)
				(justify right)
			)
		)
		(property "Value" "R_1k_0402"
			(at 257.81 242.57 0)
			(effects
				(font
					(size 1.27 1.27)
					(thickness 0.15)
				)
				(justify left bottom)
				(hide yes)
			)
		)
		(property "Footprint" "antmicro-footprints:R_0402_1005Metric"
			(at 260.35 242.57 0)
			(effects
				(font
					(size 1.27 1.27)
					(thickness 0.15)
				)
				(justify left bottom)
				(hide yes)
			)
		)
		(property "Datasheet" "https://www.bourns.com/docs/product-datasheets/cr.pdf"
			(at 262.89 242.57 0)
			(effects
				(font
					(size 1.27 1.27)
					(thickness 0.15)
				)
				(justify left bottom)
				(hide yes)
			)
		)
		(property "Description" ""
			(at 245.11 222.25 0)
			(effects
				(font
					(size 1.27 1.27)
				)
				(hide yes)
			)
		)
		(property "MPN" "CR0402-FX-1001GLF"
			(at 265.43 242.57 0)
			(effects
				(font
					(size 1.27 1.27)
					(thickness 0.15)
				)
				(justify left bottom)
				(hide yes)
			)
		)
		(property "Manufacturer" "Bourns"
			(at 267.97 242.57 0)
			(effects
				(font
					(size 1.27 1.27)
					(thickness 0.15)
				)
				(justify left bottom)
				(hide yes)
			)
		)
		(property "License" "Apache-2.0"
			(at 270.51 242.57 0)
			(effects
				(font
					(size 1.27 1.27)
					(thickness 0.15)
				)
				(justify left bottom)
				(hide yes)
			)
		)
		(property "Author" "Antmicro"
			(at 273.05 242.57 0)
			(effects
				(font
					(size 1.27 1.27)
					(thickness 0.15)
				)
				(justify left bottom)
				(hide yes)
			)
		)
		(property "Val" "1k"
			(at 243.84 222.25 0)
			(effects
				(font
					(size 1.27 1.27)
					(thickness 0.15)
				)
				(justify right)
			)
		)
		(property "Tolerance" "1%"
			(at 255.27 242.57 0)
			(effects
				(font
					(size 1.27 1.27)
				)
				(justify left bottom)
				(hide yes)
			)
		)
		(property "Public" "False"
			(at 275.59 242.57 0)
			(effects
				(font
					(size 1.27 1.27)
				)
				(justify left bottom)
				(hide yes)
			)
		)
		(pin "1"
		)
		(pin "2"
		)
		(instances
			(project "com-express-7-baseboard"
				(path ""
					(reference "R227")
					(unit 1)
				)
			)
		)
	)
	(symbol
		(lib_id "antmicropower:GND")
		(at 170.18 152.4 0)
		(unit 1)
		(exclude_from_sim no)
		(in_bom yes)
		(on_board yes)
		(dnp no)
		(property "Reference" "#PWR0308"
			(at 179.07 154.94 0)
			(effects
				(font
					(size 1.27 1.27)
					(thickness 0.15)
				)
				(justify left bottom)
				(hide yes)
			)
		)
		(property "Value" "GND"
			(at 170.18 156.21 0)
			(effects
				(font
					(size 1.27 1.27)
					(thickness 0.15)
				)
			)
		)
		(property "Footprint" ""
			(at 179.07 160.02 0)
			(effects
				(font
					(size 1.27 1.27)
					(thickness 0.15)
				)
				(justify left bottom)
				(hide yes)
			)
		)
		(property "Datasheet" ""
			(at 179.07 165.1 0)
			(effects
				(font
					(size 1.27 1.27)
					(thickness 0.15)
				)
				(justify left bottom)
				(hide yes)
			)
		)
		(property "Description" ""
			(at 170.18 152.4 0)
			(effects
				(font
					(size 1.27 1.27)
				)
				(hide yes)
			)
		)
		(property "Author" "Antmicro"
			(at 179.07 160.02 0)
			(effects
				(font
					(size 1.27 1.27)
					(thickness 0.15)
				)
				(justify left bottom)
				(hide yes)
			)
		)
		(property "License" "Apache-2.0"
			(at 179.07 162.56 0)
			(effects
				(font
					(size 1.27 1.27)
					(thickness 0.15)
				)
				(justify left bottom)
				(hide yes)
			)
		)
		(pin "1"
		)
		(instances
			(project "com-express-7-baseboard"
				(path ""
					(reference "#PWR0308")
					(unit 1)
				)
			)
		)
	)
	(symbol
		(lib_id "antmicroCapacitors0402:C_100n_0402")
		(at 140.97 30.48 90)
		(unit 1)
		(exclude_from_sim no)
		(in_bom yes)
		(on_board yes)
		(dnp no)
		(fields_autoplaced yes)
		(property "Reference" "C113"
			(at 143.51 26.6636 90)
			(effects
				(font
					(size 1.27 1.27)
					(thickness 0.15)
				)
				(justify right)
			)
		)
		(property "Value" "C_100n_0402"
			(at 151.13 10.16 0)
			(effects
				(font
					(size 1.27 1.27)
					(thickness 0.15)
				)
				(justify left bottom)
				(hide yes)
			)
		)
		(property "Footprint" "antmicro-footprints:C_0402_1005Metric"
			(at 153.67 10.16 0)
			(effects
				(font
					(size 1.27 1.27)
					(thickness 0.15)
				)
				(justify left bottom)
				(hide yes)
			)
		)
		(property "Datasheet" "https://www.murata.com/products/productdetail?partno=GRM155R61H104KE14%23"
			(at 156.21 10.16 0)
			(effects
				(font
					(size 1.27 1.27)
					(thickness 0.15)
				)
				(justify left bottom)
				(hide yes)
			)
		)
		(property "Description" ""
			(at 140.97 30.48 0)
			(effects
				(font
					(size 1.27 1.27)
				)
				(hide yes)
			)
		)
		(property "MPN" "GRM155R61H104KE14D"
			(at 158.75 10.16 0)
			(effects
				(font
					(size 1.27 1.27)
					(thickness 0.15)
				)
				(justify left bottom)
				(hide yes)
			)
		)
		(property "Manufacturer" "Murata"
			(at 161.29 10.16 0)
			(effects
				(font
					(size 1.27 1.27)
					(thickness 0.15)
				)
				(justify left bottom)
				(hide yes)
			)
		)
		(property "License" "Apache-2.0"
			(at 163.83 10.16 0)
			(effects
				(font
					(size 1.27 1.27)
					(thickness 0.15)
				)
				(justify left bottom)
				(hide yes)
			)
		)
		(property "Author" "Antmicro"
			(at 166.37 10.16 0)
			(effects
				(font
					(size 1.27 1.27)
					(thickness 0.15)
				)
				(justify left bottom)
				(hide yes)
			)
		)
		(property "Val" "100n"
			(at 143.51 29.2036 90)
			(effects
				(font
					(size 1.27 1.27)
					(thickness 0.15)
				)
				(justify right)
			)
		)
		(property "Voltage" "50V"
			(at 168.91 10.16 0)
			(effects
				(font
					(size 1.27 1.27)
				)
				(justify left bottom)
				(hide yes)
			)
		)
		(property "Dielectric" "X5R"
			(at 171.45 10.16 0)
			(effects
				(font
					(size 1.27 1.27)
				)
				(justify left bottom)
				(hide yes)
			)
		)
		(property "Public" "False"
			(at 173.99 10.16 0)
			(effects
				(font
					(size 1.27 1.27)
				)
				(justify left bottom)
				(hide yes)
			)
		)
		(pin "1"
		)
		(pin "2"
		)
		(instances
			(project "com-express-7-baseboard"
				(path ""
					(reference "C113")
					(unit 1)
				)
			)
		)
	)
	(symbol
		(lib_id "antmicroResistors0402:R_0R_0402")
		(at 179.07 219.71 0)
		(mirror x)
		(unit 1)
		(exclude_from_sim no)
		(in_bom yes)
		(on_board yes)
		(dnp no)
		(property "Reference" "R215"
			(at 181.61 222.25 0)
			(effects
				(font
					(size 1.27 1.27)
					(thickness 0.15)
				)
			)
		)
		(property "Value" "R_0R_0402"
			(at 199.39 207.01 0)
			(effects
				(font
					(size 1.27 1.27)
					(thickness 0.15)
				)
				(justify left bottom)
				(hide yes)
			)
		)
		(property "Footprint" "antmicro-footprints:R_0402_1005Metric"
			(at 199.39 204.47 0)
			(effects
				(font
					(size 1.27 1.27)
					(thickness 0.15)
				)
				(justify left bottom)
				(hide yes)
			)
		)
		(property "Datasheet" "https://industrial.panasonic.com/cdbs/www-data/pdf/RDA0000/AOA0000C301.pdf"
			(at 199.39 201.93 0)
			(effects
				(font
					(size 1.27 1.27)
					(thickness 0.15)
				)
				(justify left bottom)
				(hide yes)
			)
		)
		(property "Description" ""
			(at 179.07 219.71 0)
			(effects
				(font
					(size 1.27 1.27)
				)
				(hide yes)
			)
		)
		(property "MPN" "ERJ2GE0R00X"
			(at 199.39 199.39 0)
			(effects
				(font
					(size 1.27 1.27)
					(thickness 0.15)
				)
				(justify left bottom)
				(hide yes)
			)
		)
		(property "Manufacturer" "Panasonic"
			(at 199.39 196.85 0)
			(effects
				(font
					(size 1.27 1.27)
					(thickness 0.15)
				)
				(justify left bottom)
				(hide yes)
			)
		)
		(property "License" "Apache-2.0"
			(at 199.39 194.31 0)
			(effects
				(font
					(size 1.27 1.27)
					(thickness 0.15)
				)
				(justify left bottom)
				(hide yes)
			)
		)
		(property "Author" "Antmicro"
			(at 199.39 191.77 0)
			(effects
				(font
					(size 1.27 1.27)
					(thickness 0.15)
				)
				(justify left bottom)
				(hide yes)
			)
		)
		(property "Val" "0R"
			(at 181.61 224.79 0)
			(effects
				(font
					(size 1.27 1.27)
					(thickness 0.15)
				)
			)
		)
		(property "Tolerance" "~"
			(at 199.39 209.55 0)
			(effects
				(font
					(size 1.27 1.27)
				)
				(justify left bottom)
				(hide yes)
			)
		)
		(property "Current" "1A"
			(at 199.39 189.23 0)
			(effects
				(font
					(size 1.27 1.27)
					(thickness 0.15)
				)
				(justify left bottom)
				(hide yes)
			)
		)
		(property "Public" "False"
			(at 199.39 189.23 0)
			(effects
				(font
					(size 1.27 1.27)
				)
				(justify left bottom)
				(hide yes)
			)
		)
		(pin "1"
		)
		(pin "2"
		)
		(instances
			(project "com-express-7-baseboard"
				(path ""
					(reference "R215")
					(unit 1)
				)
			)
		)
	)
	(symbol
		(lib_id "antmicroResistors0402:R_1k_0402")
		(at 240.03 251.46 270)
		(mirror x)
		(unit 1)
		(exclude_from_sim no)
		(in_bom yes)
		(on_board yes)
		(dnp no)
		(property "Reference" "R224"
			(at 240.03 255.27 0)
			(effects
				(font
					(size 1.27 1.27)
					(thickness 0.15)
				)
				(justify right)
			)
		)
		(property "Value" "R_1k_0402"
			(at 227.33 231.14 0)
			(effects
				(font
					(size 1.27 1.27)
					(thickness 0.15)
				)
				(justify left bottom)
				(hide yes)
			)
		)
		(property "Footprint" "antmicro-footprints:R_0402_1005Metric"
			(at 224.79 231.14 0)
			(effects
				(font
					(size 1.27 1.27)
					(thickness 0.15)
				)
				(justify left bottom)
				(hide yes)
			)
		)
		(property "Datasheet" "https://www.bourns.com/docs/product-datasheets/cr.pdf"
			(at 222.25 231.14 0)
			(effects
				(font
					(size 1.27 1.27)
					(thickness 0.15)
				)
				(justify left bottom)
				(hide yes)
			)
		)
		(property "Description" ""
			(at 240.03 251.46 0)
			(effects
				(font
					(size 1.27 1.27)
				)
				(hide yes)
			)
		)
		(property "MPN" "CR0402-FX-1001GLF"
			(at 219.71 231.14 0)
			(effects
				(font
					(size 1.27 1.27)
					(thickness 0.15)
				)
				(justify left bottom)
				(hide yes)
			)
		)
		(property "Manufacturer" "Bourns"
			(at 217.17 231.14 0)
			(effects
				(font
					(size 1.27 1.27)
					(thickness 0.15)
				)
				(justify left bottom)
				(hide yes)
			)
		)
		(property "License" "Apache-2.0"
			(at 214.63 231.14 0)
			(effects
				(font
					(size 1.27 1.27)
					(thickness 0.15)
				)
				(justify left bottom)
				(hide yes)
			)
		)
		(property "Author" "Antmicro"
			(at 212.09 231.14 0)
			(effects
				(font
					(size 1.27 1.27)
					(thickness 0.15)
				)
				(justify left bottom)
				(hide yes)
			)
		)
		(property "Val" "1k"
			(at 241.3 251.46 0)
			(effects
				(font
					(size 1.27 1.27)
					(thickness 0.15)
				)
				(justify right)
			)
		)
		(property "Tolerance" "1%"
			(at 229.87 231.14 0)
			(effects
				(font
					(size 1.27 1.27)
				)
				(justify left bottom)
				(hide yes)
			)
		)
		(property "Public" "False"
			(at 209.55 231.14 0)
			(effects
				(font
					(size 1.27 1.27)
				)
				(justify left bottom)
				(hide yes)
			)
		)
		(pin "1"
		)
		(pin "2"
		)
		(instances
			(project "com-express-7-baseboard"
				(path ""
					(reference "R224")
					(unit 1)
				)
			)
		)
	)
	(symbol
		(lib_id "antmicroCapacitors0402:C_220n_0402")
		(at 154.94 191.77 0)
		(unit 1)
		(exclude_from_sim no)
		(in_bom yes)
		(on_board yes)
		(dnp no)
		(property "Reference" "C130"
			(at 153.67 190.5 0)
			(effects
				(font
					(size 1.27 1.27)
					(thickness 0.15)
				)
			)
		)
		(property "Value" "C_220n_0402"
			(at 175.26 201.93 0)
			(effects
				(font
					(size 1.27 1.27)
					(thickness 0.15)
				)
				(justify left bottom)
				(hide yes)
			)
		)
		(property "Footprint" "antmicro-footprints:C_0402_1005Metric"
			(at 175.26 204.47 0)
			(effects
				(font
					(size 1.27 1.27)
					(thickness 0.15)
				)
				(justify left bottom)
				(hide yes)
			)
		)
		(property "Datasheet" "https://www.yageo.com/en/Chart/Download/pdf/CC0402KRX5R6BB224"
			(at 175.26 207.01 0)
			(effects
				(font
					(size 1.27 1.27)
					(thickness 0.15)
				)
				(justify left bottom)
				(hide yes)
			)
		)
		(property "Description" ""
			(at 154.94 191.77 0)
			(effects
				(font
					(size 1.27 1.27)
				)
				(hide yes)
			)
		)
		(property "MPN" "CC0402KRX5R6BB224"
			(at 175.26 209.55 0)
			(effects
				(font
					(size 1.27 1.27)
					(thickness 0.15)
				)
				(justify left bottom)
				(hide yes)
			)
		)
		(property "Manufacturer" "YAGEO"
			(at 175.26 212.09 0)
			(effects
				(font
					(size 1.27 1.27)
					(thickness 0.15)
				)
				(justify left bottom)
				(hide yes)
			)
		)
		(property "License" "Apache-2.0"
			(at 175.26 214.63 0)
			(effects
				(font
					(size 1.27 1.27)
					(thickness 0.15)
				)
				(justify left bottom)
				(hide yes)
			)
		)
		(property "Author" "Antmicro"
			(at 175.26 217.17 0)
			(effects
				(font
					(size 1.27 1.27)
					(thickness 0.15)
				)
				(justify left bottom)
				(hide yes)
			)
		)
		(property "Val" "220n"
			(at 161.29 190.5 0)
			(effects
				(font
					(size 1.27 1.27)
					(thickness 0.15)
				)
			)
		)
		(property "Voltage" ""
			(at 175.26 219.71 0)
			(effects
				(font
					(size 1.27 1.27)
				)
				(justify left bottom)
				(hide yes)
			)
		)
		(property "Dielectric" ""
			(at 175.26 222.25 0)
			(effects
				(font
					(size 1.27 1.27)
				)
				(justify left bottom)
				(hide yes)
			)
		)
		(property "Public" "False"
			(at 175.26 224.79 0)
			(effects
				(font
					(size 1.27 1.27)
				)
				(justify left bottom)
				(hide yes)
			)
		)
		(pin "1"
		)
		(pin "2"
		)
		(instances
			(project "com-express-7-baseboard"
				(path ""
					(reference "C130")
					(unit 1)
				)
			)
		)
	)
	(symbol
		(lib_id "antmicroTestPoints:TP_0.75mm_SMD")
		(at 182.88 100.33 0)
		(mirror y)
		(unit 1)
		(exclude_from_sim no)
		(in_bom no)
		(on_board yes)
		(dnp no)
		(property "Reference" "TP52"
			(at 176.53 100.33 0)
			(effects
				(font
					(size 1.27 1.27)
					(thickness 0.15)
				)
			)
		)
		(property "Value" "TP_0.75mm_SMD"
			(at 172.085 104.14 0)
			(effects
				(font
					(size 1.27 1.27)
					(thickness 0.15)
				)
				(justify left bottom)
				(hide yes)
			)
		)
		(property "Footprint" "antmicro-footprints:TP_SMD_0.75mm"
			(at 172.085 106.68 0)
			(effects
				(font
					(size 1.27 1.27)
					(thickness 0.15)
				)
				(justify left bottom)
				(hide yes)
			)
		)
		(property "Datasheet" ""
			(at 165.1 113.03 0)
			(effects
				(font
					(size 1.27 1.27)
					(thickness 0.15)
				)
				(justify left bottom)
				(hide yes)
			)
		)
		(property "Description" ""
			(at 182.88 100.33 0)
			(effects
				(font
					(size 1.27 1.27)
				)
				(hide yes)
			)
		)
		(property "MPN" ""
			(at 172.085 111.76 0)
			(effects
				(font
					(size 1.27 1.27)
					(thickness 0.15)
				)
				(justify left bottom)
				(hide yes)
			)
		)
		(property "Manufacturer" ""
			(at 172.085 106.68 0)
			(effects
				(font
					(size 1.27 1.27)
					(thickness 0.15)
				)
				(justify left bottom)
				(hide yes)
			)
		)
		(property "Author" "Antmicro"
			(at 172.085 109.22 0)
			(effects
				(font
					(size 1.27 1.27)
					(thickness 0.15)
				)
				(justify left bottom)
				(hide yes)
			)
		)
		(property "License" "Apache-2.0"
			(at 172.085 111.76 0)
			(effects
				(font
					(size 1.27 1.27)
					(thickness 0.15)
				)
				(justify left bottom)
				(hide yes)
			)
		)
		(property "Public" "False"
			(at 172.72 114.3 0)
			(effects
				(font
					(size 1.27 1.27)
				)
				(justify left bottom)
				(hide yes)
			)
		)
		(pin "1"
		)
		(instances
			(project "com-express-7-baseboard"
				(path ""
					(reference "TP52")
					(unit 1)
				)
			)
		)
	)
	(symbol
		(lib_id "antmicropower:GND")
		(at 165.1 96.52 0)
		(unit 1)
		(exclude_from_sim no)
		(in_bom yes)
		(on_board yes)
		(dnp no)
		(property "Reference" "#PWR0305"
			(at 173.99 99.06 0)
			(effects
				(font
					(size 1.27 1.27)
					(thickness 0.15)
				)
				(justify left bottom)
				(hide yes)
			)
		)
		(property "Value" "GND"
			(at 168.91 97.79 0)
			(effects
				(font
					(size 1.27 1.27)
					(thickness 0.15)
				)
			)
		)
		(property "Footprint" ""
			(at 173.99 104.14 0)
			(effects
				(font
					(size 1.27 1.27)
					(thickness 0.15)
				)
				(justify left bottom)
				(hide yes)
			)
		)
		(property "Datasheet" ""
			(at 173.99 109.22 0)
			(effects
				(font
					(size 1.27 1.27)
					(thickness 0.15)
				)
				(justify left bottom)
				(hide yes)
			)
		)
		(property "Description" ""
			(at 165.1 96.52 0)
			(effects
				(font
					(size 1.27 1.27)
				)
				(hide yes)
			)
		)
		(property "Author" "Antmicro"
			(at 173.99 104.14 0)
			(effects
				(font
					(size 1.27 1.27)
					(thickness 0.15)
				)
				(justify left bottom)
				(hide yes)
			)
		)
		(property "License" "Apache-2.0"
			(at 173.99 106.68 0)
			(effects
				(font
					(size 1.27 1.27)
					(thickness 0.15)
				)
				(justify left bottom)
				(hide yes)
			)
		)
		(pin "1"
		)
		(instances
			(project "com-express-7-baseboard"
				(path ""
					(reference "#PWR0305")
					(unit 1)
				)
			)
		)
	)
	(symbol
		(lib_id "antmicroResistors0402:R_1k_0402")
		(at 158.75 127 90)
		(unit 1)
		(exclude_from_sim no)
		(in_bom yes)
		(on_board yes)
		(dnp yes)
		(property "Reference" "R213"
			(at 158.75 130.81 0)
			(effects
				(font
					(size 1.27 1.27)
					(thickness 0.15)
				)
				(justify right)
			)
		)
		(property "Value" "R_1k_0402"
			(at 171.45 106.68 0)
			(effects
				(font
					(size 1.27 1.27)
					(thickness 0.15)
				)
				(justify left bottom)
				(hide yes)
			)
		)
		(property "Footprint" "antmicro-footprints:R_0402_1005Metric"
			(at 173.99 106.68 0)
			(effects
				(font
					(size 1.27 1.27)
					(thickness 0.15)
				)
				(justify left bottom)
				(hide yes)
			)
		)
		(property "Datasheet" "https://www.bourns.com/docs/product-datasheets/cr.pdf"
			(at 176.53 106.68 0)
			(effects
				(font
					(size 1.27 1.27)
					(thickness 0.15)
				)
				(justify left bottom)
				(hide yes)
			)
		)
		(property "Description" ""
			(at 158.75 127 0)
			(effects
				(font
					(size 1.27 1.27)
				)
				(hide yes)
			)
		)
		(property "MPN" "CR0402-FX-1001GLF"
			(at 179.07 106.68 0)
			(effects
				(font
					(size 1.27 1.27)
					(thickness 0.15)
				)
				(justify left bottom)
				(hide yes)
			)
		)
		(property "Manufacturer" "Bourns"
			(at 181.61 106.68 0)
			(effects
				(font
					(size 1.27 1.27)
					(thickness 0.15)
				)
				(justify left bottom)
				(hide yes)
			)
		)
		(property "License" "Apache-2.0"
			(at 184.15 106.68 0)
			(effects
				(font
					(size 1.27 1.27)
					(thickness 0.15)
				)
				(justify left bottom)
				(hide yes)
			)
		)
		(property "Author" "Antmicro"
			(at 186.69 106.68 0)
			(effects
				(font
					(size 1.27 1.27)
					(thickness 0.15)
				)
				(justify left bottom)
				(hide yes)
			)
		)
		(property "Val" "1k"
			(at 157.48 127 0)
			(effects
				(font
					(size 1.27 1.27)
					(thickness 0.15)
				)
				(justify right)
			)
		)
		(property "Tolerance" "1%"
			(at 168.91 106.68 0)
			(effects
				(font
					(size 1.27 1.27)
				)
				(justify left bottom)
				(hide yes)
			)
		)
		(property "Public" "False"
			(at 189.23 106.68 0)
			(effects
				(font
					(size 1.27 1.27)
				)
				(justify left bottom)
				(hide yes)
			)
		)
		(pin "1"
		)
		(pin "2"
		)
		(instances
			(project "com-express-7-baseboard"
				(path ""
					(reference "R213")
					(unit 1)
				)
			)
		)
	)
	(symbol
		(lib_id "antmicroCapacitors0402:C_220n_0402")
		(at 154.94 207.01 0)
		(unit 1)
		(exclude_from_sim no)
		(in_bom yes)
		(on_board yes)
		(dnp no)
		(property "Reference" "C132"
			(at 153.67 205.74 0)
			(effects
				(font
					(size 1.27 1.27)
					(thickness 0.15)
				)
			)
		)
		(property "Value" "C_220n_0402"
			(at 175.26 217.17 0)
			(effects
				(font
					(size 1.27 1.27)
					(thickness 0.15)
				)
				(justify left bottom)
				(hide yes)
			)
		)
		(property "Footprint" "antmicro-footprints:C_0402_1005Metric"
			(at 175.26 219.71 0)
			(effects
				(font
					(size 1.27 1.27)
					(thickness 0.15)
				)
				(justify left bottom)
				(hide yes)
			)
		)
		(property "Datasheet" "https://www.yageo.com/en/Chart/Download/pdf/CC0402KRX5R6BB224"
			(at 175.26 222.25 0)
			(effects
				(font
					(size 1.27 1.27)
					(thickness 0.15)
				)
				(justify left bottom)
				(hide yes)
			)
		)
		(property "Description" ""
			(at 154.94 207.01 0)
			(effects
				(font
					(size 1.27 1.27)
				)
				(hide yes)
			)
		)
		(property "MPN" "CC0402KRX5R6BB224"
			(at 175.26 224.79 0)
			(effects
				(font
					(size 1.27 1.27)
					(thickness 0.15)
				)
				(justify left bottom)
				(hide yes)
			)
		)
		(property "Manufacturer" "YAGEO"
			(at 175.26 227.33 0)
			(effects
				(font
					(size 1.27 1.27)
					(thickness 0.15)
				)
				(justify left bottom)
				(hide yes)
			)
		)
		(property "License" "Apache-2.0"
			(at 175.26 229.87 0)
			(effects
				(font
					(size 1.27 1.27)
					(thickness 0.15)
				)
				(justify left bottom)
				(hide yes)
			)
		)
		(property "Author" "Antmicro"
			(at 175.26 232.41 0)
			(effects
				(font
					(size 1.27 1.27)
					(thickness 0.15)
				)
				(justify left bottom)
				(hide yes)
			)
		)
		(property "Val" "220n"
			(at 161.29 205.74 0)
			(effects
				(font
					(size 1.27 1.27)
					(thickness 0.15)
				)
			)
		)
		(property "Voltage" ""
			(at 175.26 234.95 0)
			(effects
				(font
					(size 1.27 1.27)
				)
				(justify left bottom)
				(hide yes)
			)
		)
		(property "Dielectric" ""
			(at 175.26 237.49 0)
			(effects
				(font
					(size 1.27 1.27)
				)
				(justify left bottom)
				(hide yes)
			)
		)
		(property "Public" "False"
			(at 175.26 240.03 0)
			(effects
				(font
					(size 1.27 1.27)
				)
				(justify left bottom)
				(hide yes)
			)
		)
		(pin "1"
		)
		(pin "2"
		)
		(instances
			(project "com-express-7-baseboard"
				(path ""
					(reference "C132")
					(unit 1)
				)
			)
		)
	)
	(symbol
		(lib_id "antmicroCapacitors0402:C_220n_0402")
		(at 154.94 199.39 0)
		(unit 1)
		(exclude_from_sim no)
		(in_bom yes)
		(on_board yes)
		(dnp no)
		(property "Reference" "C131"
			(at 153.67 198.12 0)
			(effects
				(font
					(size 1.27 1.27)
					(thickness 0.15)
				)
			)
		)
		(property "Value" "C_220n_0402"
			(at 175.26 209.55 0)
			(effects
				(font
					(size 1.27 1.27)
					(thickness 0.15)
				)
				(justify left bottom)
				(hide yes)
			)
		)
		(property "Footprint" "antmicro-footprints:C_0402_1005Metric"
			(at 175.26 212.09 0)
			(effects
				(font
					(size 1.27 1.27)
					(thickness 0.15)
				)
				(justify left bottom)
				(hide yes)
			)
		)
		(property "Datasheet" "https://www.yageo.com/en/Chart/Download/pdf/CC0402KRX5R6BB224"
			(at 175.26 214.63 0)
			(effects
				(font
					(size 1.27 1.27)
					(thickness 0.15)
				)
				(justify left bottom)
				(hide yes)
			)
		)
		(property "Description" ""
			(at 154.94 199.39 0)
			(effects
				(font
					(size 1.27 1.27)
				)
				(hide yes)
			)
		)
		(property "MPN" "CC0402KRX5R6BB224"
			(at 175.26 217.17 0)
			(effects
				(font
					(size 1.27 1.27)
					(thickness 0.15)
				)
				(justify left bottom)
				(hide yes)
			)
		)
		(property "Manufacturer" "YAGEO"
			(at 175.26 219.71 0)
			(effects
				(font
					(size 1.27 1.27)
					(thickness 0.15)
				)
				(justify left bottom)
				(hide yes)
			)
		)
		(property "License" "Apache-2.0"
			(at 175.26 222.25 0)
			(effects
				(font
					(size 1.27 1.27)
					(thickness 0.15)
				)
				(justify left bottom)
				(hide yes)
			)
		)
		(property "Author" "Antmicro"
			(at 175.26 224.79 0)
			(effects
				(font
					(size 1.27 1.27)
					(thickness 0.15)
				)
				(justify left bottom)
				(hide yes)
			)
		)
		(property "Val" "220n"
			(at 161.29 198.12 0)
			(effects
				(font
					(size 1.27 1.27)
					(thickness 0.15)
				)
			)
		)
		(property "Voltage" ""
			(at 175.26 227.33 0)
			(effects
				(font
					(size 1.27 1.27)
				)
				(justify left bottom)
				(hide yes)
			)
		)
		(property "Dielectric" ""
			(at 175.26 229.87 0)
			(effects
				(font
					(size 1.27 1.27)
				)
				(justify left bottom)
				(hide yes)
			)
		)
		(property "Public" "False"
			(at 175.26 232.41 0)
			(effects
				(font
					(size 1.27 1.27)
				)
				(justify left bottom)
				(hide yes)
			)
		)
		(pin "1"
		)
		(pin "2"
		)
		(instances
			(project "com-express-7-baseboard"
				(path ""
					(reference "C131")
					(unit 1)
				)
			)
		)
	)
	(symbol
		(lib_id "antmicroCapacitors0402:C_220n_0402")
		(at 152.4 186.69 0)
		(unit 1)
		(exclude_from_sim no)
		(in_bom yes)
		(on_board yes)
		(dnp no)
		(property "Reference" "C123"
			(at 151.13 187.96 0)
			(effects
				(font
					(size 1.27 1.27)
					(thickness 0.15)
				)
			)
		)
		(property "Value" "C_220n_0402"
			(at 172.72 196.85 0)
			(effects
				(font
					(size 1.27 1.27)
					(thickness 0.15)
				)
				(justify left bottom)
				(hide yes)
			)
		)
		(property "Footprint" "antmicro-footprints:C_0402_1005Metric"
			(at 172.72 199.39 0)
			(effects
				(font
					(size 1.27 1.27)
					(thickness 0.15)
				)
				(justify left bottom)
				(hide yes)
			)
		)
		(property "Datasheet" "https://www.yageo.com/en/Chart/Download/pdf/CC0402KRX5R6BB224"
			(at 172.72 201.93 0)
			(effects
				(font
					(size 1.27 1.27)
					(thickness 0.15)
				)
				(justify left bottom)
				(hide yes)
			)
		)
		(property "Description" ""
			(at 152.4 186.69 0)
			(effects
				(font
					(size 1.27 1.27)
				)
				(hide yes)
			)
		)
		(property "MPN" "CC0402KRX5R6BB224"
			(at 172.72 204.47 0)
			(effects
				(font
					(size 1.27 1.27)
					(thickness 0.15)
				)
				(justify left bottom)
				(hide yes)
			)
		)
		(property "Manufacturer" "YAGEO"
			(at 172.72 207.01 0)
			(effects
				(font
					(size 1.27 1.27)
					(thickness 0.15)
				)
				(justify left bottom)
				(hide yes)
			)
		)
		(property "License" "Apache-2.0"
			(at 172.72 209.55 0)
			(effects
				(font
					(size 1.27 1.27)
					(thickness 0.15)
				)
				(justify left bottom)
				(hide yes)
			)
		)
		(property "Author" "Antmicro"
			(at 172.72 212.09 0)
			(effects
				(font
					(size 1.27 1.27)
					(thickness 0.15)
				)
				(justify left bottom)
				(hide yes)
			)
		)
		(property "Val" "220n"
			(at 158.75 187.96 0)
			(effects
				(font
					(size 1.27 1.27)
					(thickness 0.15)
				)
			)
		)
		(property "Voltage" ""
			(at 172.72 214.63 0)
			(effects
				(font
					(size 1.27 1.27)
				)
				(justify left bottom)
				(hide yes)
			)
		)
		(property "Dielectric" ""
			(at 172.72 217.17 0)
			(effects
				(font
					(size 1.27 1.27)
				)
				(justify left bottom)
				(hide yes)
			)
		)
		(property "Public" "False"
			(at 172.72 219.71 0)
			(effects
				(font
					(size 1.27 1.27)
				)
				(justify left bottom)
				(hide yes)
			)
		)
		(pin "1"
		)
		(pin "2"
		)
		(instances
			(project "com-express-7-baseboard"
				(path ""
					(reference "C123")
					(unit 1)
				)
			)
		)
	)
	(symbol
		(lib_id "antmicroCapacitors0402:C_100n_0402")
		(at 179.07 152.4 90)
		(unit 1)
		(exclude_from_sim no)
		(in_bom yes)
		(on_board yes)
		(dnp no)
		(fields_autoplaced yes)
		(property "Reference" "C135"
			(at 181.61 148.5836 90)
			(effects
				(font
					(size 1.27 1.27)
					(thickness 0.15)
				)
				(justify right)
			)
		)
		(property "Value" "C_100n_0402"
			(at 189.23 132.08 0)
			(effects
				(font
					(size 1.27 1.27)
					(thickness 0.15)
				)
				(justify left bottom)
				(hide yes)
			)
		)
		(property "Footprint" "antmicro-footprints:C_0402_1005Metric"
			(at 191.77 132.08 0)
			(effects
				(font
					(size 1.27 1.27)
					(thickness 0.15)
				)
				(justify left bottom)
				(hide yes)
			)
		)
		(property "Datasheet" "https://www.murata.com/products/productdetail?partno=GRM155R61H104KE14%23"
			(at 194.31 132.08 0)
			(effects
				(font
					(size 1.27 1.27)
					(thickness 0.15)
				)
				(justify left bottom)
				(hide yes)
			)
		)
		(property "Description" ""
			(at 179.07 152.4 0)
			(effects
				(font
					(size 1.27 1.27)
				)
				(hide yes)
			)
		)
		(property "MPN" "GRM155R61H104KE14D"
			(at 196.85 132.08 0)
			(effects
				(font
					(size 1.27 1.27)
					(thickness 0.15)
				)
				(justify left bottom)
				(hide yes)
			)
		)
		(property "Manufacturer" "Murata"
			(at 199.39 132.08 0)
			(effects
				(font
					(size 1.27 1.27)
					(thickness 0.15)
				)
				(justify left bottom)
				(hide yes)
			)
		)
		(property "License" "Apache-2.0"
			(at 201.93 132.08 0)
			(effects
				(font
					(size 1.27 1.27)
					(thickness 0.15)
				)
				(justify left bottom)
				(hide yes)
			)
		)
		(property "Author" "Antmicro"
			(at 204.47 132.08 0)
			(effects
				(font
					(size 1.27 1.27)
					(thickness 0.15)
				)
				(justify left bottom)
				(hide yes)
			)
		)
		(property "Val" "100n"
			(at 181.61 151.1236 90)
			(effects
				(font
					(size 1.27 1.27)
					(thickness 0.15)
				)
				(justify right)
			)
		)
		(property "Voltage" "50V"
			(at 207.01 132.08 0)
			(effects
				(font
					(size 1.27 1.27)
				)
				(justify left bottom)
				(hide yes)
			)
		)
		(property "Dielectric" "X5R"
			(at 209.55 132.08 0)
			(effects
				(font
					(size 1.27 1.27)
				)
				(justify left bottom)
				(hide yes)
			)
		)
		(property "Public" "False"
			(at 212.09 132.08 0)
			(effects
				(font
					(size 1.27 1.27)
				)
				(justify left bottom)
				(hide yes)
			)
		)
		(pin "1"
		)
		(pin "2"
		)
		(instances
			(project "com-express-7-baseboard"
				(path ""
					(reference "C135")
					(unit 1)
				)
			)
		)
	)
	(symbol
		(lib_id "antmicropower:+3V3")
		(at 143.51 92.71 0)
		(unit 1)
		(exclude_from_sim no)
		(in_bom yes)
		(on_board yes)
		(dnp no)
		(property "Reference" "#PWR0294"
			(at 158.75 92.71 0)
			(effects
				(font
					(size 1.27 1.27)
					(thickness 0.15)
				)
				(justify left bottom)
				(hide yes)
			)
		)
		(property "Value" "+3V3"
			(at 142.24 88.9 0)
			(effects
				(font
					(size 1.27 1.27)
					(thickness 0.15)
				)
			)
		)
		(property "Footprint" ""
			(at 158.75 100.33 0)
			(effects
				(font
					(size 1.27 1.27)
					(thickness 0.15)
				)
				(justify left bottom)
				(hide yes)
			)
		)
		(property "Datasheet" ""
			(at 158.75 102.87 0)
			(effects
				(font
					(size 1.27 1.27)
					(thickness 0.15)
				)
				(justify left bottom)
				(hide yes)
			)
		)
		(property "Description" ""
			(at 143.51 92.71 0)
			(effects
				(font
					(size 1.27 1.27)
				)
				(hide yes)
			)
		)
		(property "Author" "Antmicro"
			(at 158.75 95.25 0)
			(effects
				(font
					(size 1.27 1.27)
					(thickness 0.15)
				)
				(justify left bottom)
				(hide yes)
			)
		)
		(property "License" "Apache-2.0"
			(at 158.75 97.79 0)
			(effects
				(font
					(size 1.27 1.27)
					(thickness 0.15)
				)
				(justify left bottom)
				(hide yes)
			)
		)
		(pin "1"
		)
		(instances
			(project "com-express-7-baseboard"
				(path ""
					(reference "#PWR0294")
					(unit 1)
				)
			)
		)
	)
	(symbol
		(lib_id "antmicropower:GND")
		(at 179.07 167.64 0)
		(unit 1)
		(exclude_from_sim no)
		(in_bom yes)
		(on_board yes)
		(dnp no)
		(property "Reference" "#PWR0312"
			(at 187.96 170.18 0)
			(effects
				(font
					(size 1.27 1.27)
					(thickness 0.15)
				)
				(justify left bottom)
				(hide yes)
			)
		)
		(property "Value" "GND"
			(at 179.07 171.45 0)
			(effects
				(font
					(size 1.27 1.27)
					(thickness 0.15)
				)
			)
		)
		(property "Footprint" ""
			(at 187.96 175.26 0)
			(effects
				(font
					(size 1.27 1.27)
					(thickness 0.15)
				)
				(justify left bottom)
				(hide yes)
			)
		)
		(property "Datasheet" ""
			(at 187.96 180.34 0)
			(effects
				(font
					(size 1.27 1.27)
					(thickness 0.15)
				)
				(justify left bottom)
				(hide yes)
			)
		)
		(property "Description" ""
			(at 179.07 167.64 0)
			(effects
				(font
					(size 1.27 1.27)
				)
				(hide yes)
			)
		)
		(property "Author" "Antmicro"
			(at 187.96 175.26 0)
			(effects
				(font
					(size 1.27 1.27)
					(thickness 0.15)
				)
				(justify left bottom)
				(hide yes)
			)
		)
		(property "License" "Apache-2.0"
			(at 187.96 177.8 0)
			(effects
				(font
					(size 1.27 1.27)
					(thickness 0.15)
				)
				(justify left bottom)
				(hide yes)
			)
		)
		(pin "1"
		)
		(instances
			(project "com-express-7-baseboard"
				(path ""
					(reference "#PWR0312")
					(unit 1)
				)
			)
		)
	)
	(symbol
		(lib_id "antmicropower:GND")
		(at 187.96 167.64 0)
		(unit 1)
		(exclude_from_sim no)
		(in_bom yes)
		(on_board yes)
		(dnp no)
		(property "Reference" "#PWR0315"
			(at 196.85 170.18 0)
			(effects
				(font
					(size 1.27 1.27)
					(thickness 0.15)
				)
				(justify left bottom)
				(hide yes)
			)
		)
		(property "Value" "GND"
			(at 187.96 171.45 0)
			(effects
				(font
					(size 1.27 1.27)
					(thickness 0.15)
				)
			)
		)
		(property "Footprint" ""
			(at 196.85 175.26 0)
			(effects
				(font
					(size 1.27 1.27)
					(thickness 0.15)
				)
				(justify left bottom)
				(hide yes)
			)
		)
		(property "Datasheet" ""
			(at 196.85 180.34 0)
			(effects
				(font
					(size 1.27 1.27)
					(thickness 0.15)
				)
				(justify left bottom)
				(hide yes)
			)
		)
		(property "Description" ""
			(at 187.96 167.64 0)
			(effects
				(font
					(size 1.27 1.27)
				)
				(hide yes)
			)
		)
		(property "Author" "Antmicro"
			(at 196.85 175.26 0)
			(effects
				(font
					(size 1.27 1.27)
					(thickness 0.15)
				)
				(justify left bottom)
				(hide yes)
			)
		)
		(property "License" "Apache-2.0"
			(at 196.85 177.8 0)
			(effects
				(font
					(size 1.27 1.27)
					(thickness 0.15)
				)
				(justify left bottom)
				(hide yes)
			)
		)
		(pin "1"
		)
		(instances
			(project "com-express-7-baseboard"
				(path ""
					(reference "#PWR0315")
					(unit 1)
				)
			)
		)
	)
	(symbol
		(lib_id "antmicropower:+3V3")
		(at 215.9 93.98 0)
		(unit 1)
		(exclude_from_sim no)
		(in_bom yes)
		(on_board yes)
		(dnp no)
		(property "Reference" "#PWR0317"
			(at 231.14 93.98 0)
			(effects
				(font
					(size 1.27 1.27)
					(thickness 0.15)
				)
				(justify left bottom)
				(hide yes)
			)
		)
		(property "Value" "+3V3"
			(at 219.71 92.71 0)
			(effects
				(font
					(size 1.27 1.27)
					(thickness 0.15)
				)
			)
		)
		(property "Footprint" ""
			(at 231.14 101.6 0)
			(effects
				(font
					(size 1.27 1.27)
					(thickness 0.15)
				)
				(justify left bottom)
				(hide yes)
			)
		)
		(property "Datasheet" ""
			(at 231.14 104.14 0)
			(effects
				(font
					(size 1.27 1.27)
					(thickness 0.15)
				)
				(justify left bottom)
				(hide yes)
			)
		)
		(property "Description" ""
			(at 215.9 93.98 0)
			(effects
				(font
					(size 1.27 1.27)
				)
				(hide yes)
			)
		)
		(property "Author" "Antmicro"
			(at 231.14 96.52 0)
			(effects
				(font
					(size 1.27 1.27)
					(thickness 0.15)
				)
				(justify left bottom)
				(hide yes)
			)
		)
		(property "License" "Apache-2.0"
			(at 231.14 99.06 0)
			(effects
				(font
					(size 1.27 1.27)
					(thickness 0.15)
				)
				(justify left bottom)
				(hide yes)
			)
		)
		(pin "1"
		)
		(instances
			(project "com-express-7-baseboard"
				(path ""
					(reference "#PWR0317")
					(unit 1)
				)
			)
		)
	)
	(symbol
		(lib_id "antmicroCapacitors0402:C_100n_0402")
		(at 158.75 30.48 90)
		(unit 1)
		(exclude_from_sim no)
		(in_bom yes)
		(on_board yes)
		(dnp no)
		(fields_autoplaced yes)
		(property "Reference" "C119"
			(at 161.29 26.6636 90)
			(effects
				(font
					(size 1.27 1.27)
					(thickness 0.15)
				)
				(justify right)
			)
		)
		(property "Value" "C_100n_0402"
			(at 168.91 10.16 0)
			(effects
				(font
					(size 1.27 1.27)
					(thickness 0.15)
				)
				(justify left bottom)
				(hide yes)
			)
		)
		(property "Footprint" "antmicro-footprints:C_0402_1005Metric"
			(at 171.45 10.16 0)
			(effects
				(font
					(size 1.27 1.27)
					(thickness 0.15)
				)
				(justify left bottom)
				(hide yes)
			)
		)
		(property "Datasheet" "https://www.murata.com/products/productdetail?partno=GRM155R61H104KE14%23"
			(at 173.99 10.16 0)
			(effects
				(font
					(size 1.27 1.27)
					(thickness 0.15)
				)
				(justify left bottom)
				(hide yes)
			)
		)
		(property "Description" ""
			(at 158.75 30.48 0)
			(effects
				(font
					(size 1.27 1.27)
				)
				(hide yes)
			)
		)
		(property "MPN" "GRM155R61H104KE14D"
			(at 176.53 10.16 0)
			(effects
				(font
					(size 1.27 1.27)
					(thickness 0.15)
				)
				(justify left bottom)
				(hide yes)
			)
		)
		(property "Manufacturer" "Murata"
			(at 179.07 10.16 0)
			(effects
				(font
					(size 1.27 1.27)
					(thickness 0.15)
				)
				(justify left bottom)
				(hide yes)
			)
		)
		(property "License" "Apache-2.0"
			(at 181.61 10.16 0)
			(effects
				(font
					(size 1.27 1.27)
					(thickness 0.15)
				)
				(justify left bottom)
				(hide yes)
			)
		)
		(property "Author" "Antmicro"
			(at 184.15 10.16 0)
			(effects
				(font
					(size 1.27 1.27)
					(thickness 0.15)
				)
				(justify left bottom)
				(hide yes)
			)
		)
		(property "Val" "100n"
			(at 161.29 29.2036 90)
			(effects
				(font
					(size 1.27 1.27)
					(thickness 0.15)
				)
				(justify right)
			)
		)
		(property "Voltage" "50V"
			(at 186.69 10.16 0)
			(effects
				(font
					(size 1.27 1.27)
				)
				(justify left bottom)
				(hide yes)
			)
		)
		(property "Dielectric" "X5R"
			(at 189.23 10.16 0)
			(effects
				(font
					(size 1.27 1.27)
				)
				(justify left bottom)
				(hide yes)
			)
		)
		(property "Public" "False"
			(at 191.77 10.16 0)
			(effects
				(font
					(size 1.27 1.27)
				)
				(justify left bottom)
				(hide yes)
			)
		)
		(pin "1"
		)
		(pin "2"
		)
		(instances
			(project "com-express-7-baseboard"
				(path ""
					(reference "C119")
					(unit 1)
				)
			)
		)
	)
	(symbol
		(lib_id "antmicroTestPoints:TP_0.75mm_SMD")
		(at 210.82 222.25 0)
		(unit 1)
		(exclude_from_sim no)
		(in_bom no)
		(on_board yes)
		(dnp no)
		(property "Reference" "TP55"
			(at 217.17 222.25 0)
			(effects
				(font
					(size 1.27 1.27)
					(thickness 0.15)
				)
			)
		)
		(property "Value" "TP_0.75mm_SMD"
			(at 221.615 226.06 0)
			(effects
				(font
					(size 1.27 1.27)
					(thickness 0.15)
				)
				(justify left bottom)
				(hide yes)
			)
		)
		(property "Footprint" "antmicro-footprints:TP_SMD_0.75mm"
			(at 221.615 228.6 0)
			(effects
				(font
					(size 1.27 1.27)
					(thickness 0.15)
				)
				(justify left bottom)
				(hide yes)
			)
		)
		(property "Datasheet" ""
			(at 228.6 234.95 0)
			(effects
				(font
					(size 1.27 1.27)
					(thickness 0.15)
				)
				(justify left bottom)
				(hide yes)
			)
		)
		(property "Description" ""
			(at 210.82 222.25 0)
			(effects
				(font
					(size 1.27 1.27)
				)
				(hide yes)
			)
		)
		(property "MPN" ""
			(at 221.615 233.68 0)
			(effects
				(font
					(size 1.27 1.27)
					(thickness 0.15)
				)
				(justify left bottom)
				(hide yes)
			)
		)
		(property "Manufacturer" ""
			(at 221.615 228.6 0)
			(effects
				(font
					(size 1.27 1.27)
					(thickness 0.15)
				)
				(justify left bottom)
				(hide yes)
			)
		)
		(property "Author" "Antmicro"
			(at 221.615 231.14 0)
			(effects
				(font
					(size 1.27 1.27)
					(thickness 0.15)
				)
				(justify left bottom)
				(hide yes)
			)
		)
		(property "License" "Apache-2.0"
			(at 221.615 233.68 0)
			(effects
				(font
					(size 1.27 1.27)
					(thickness 0.15)
				)
				(justify left bottom)
				(hide yes)
			)
		)
		(property "Public" "False"
			(at 220.98 236.22 0)
			(effects
				(font
					(size 1.27 1.27)
				)
				(justify left bottom)
				(hide yes)
			)
		)
		(pin "1"
		)
		(instances
			(project "com-express-7-baseboard"
				(path ""
					(reference "TP55")
					(unit 1)
				)
			)
		)
	)
	(symbol
		(lib_id "antmicroCapacitors0402:C_100n_0402")
		(at 167.64 30.48 90)
		(unit 1)
		(exclude_from_sim no)
		(in_bom yes)
		(on_board yes)
		(dnp no)
		(fields_autoplaced yes)
		(property "Reference" "C127"
			(at 170.18 26.6636 90)
			(effects
				(font
					(size 1.27 1.27)
					(thickness 0.15)
				)
				(justify right)
			)
		)
		(property "Value" "C_100n_0402"
			(at 177.8 10.16 0)
			(effects
				(font
					(size 1.27 1.27)
					(thickness 0.15)
				)
				(justify left bottom)
				(hide yes)
			)
		)
		(property "Footprint" "antmicro-footprints:C_0402_1005Metric"
			(at 180.34 10.16 0)
			(effects
				(font
					(size 1.27 1.27)
					(thickness 0.15)
				)
				(justify left bottom)
				(hide yes)
			)
		)
		(property "Datasheet" "https://www.murata.com/products/productdetail?partno=GRM155R61H104KE14%23"
			(at 182.88 10.16 0)
			(effects
				(font
					(size 1.27 1.27)
					(thickness 0.15)
				)
				(justify left bottom)
				(hide yes)
			)
		)
		(property "Description" ""
			(at 167.64 30.48 0)
			(effects
				(font
					(size 1.27 1.27)
				)
				(hide yes)
			)
		)
		(property "MPN" "GRM155R61H104KE14D"
			(at 185.42 10.16 0)
			(effects
				(font
					(size 1.27 1.27)
					(thickness 0.15)
				)
				(justify left bottom)
				(hide yes)
			)
		)
		(property "Manufacturer" "Murata"
			(at 187.96 10.16 0)
			(effects
				(font
					(size 1.27 1.27)
					(thickness 0.15)
				)
				(justify left bottom)
				(hide yes)
			)
		)
		(property "License" "Apache-2.0"
			(at 190.5 10.16 0)
			(effects
				(font
					(size 1.27 1.27)
					(thickness 0.15)
				)
				(justify left bottom)
				(hide yes)
			)
		)
		(property "Author" "Antmicro"
			(at 193.04 10.16 0)
			(effects
				(font
					(size 1.27 1.27)
					(thickness 0.15)
				)
				(justify left bottom)
				(hide yes)
			)
		)
		(property "Val" "100n"
			(at 170.18 29.2036 90)
			(effects
				(font
					(size 1.27 1.27)
					(thickness 0.15)
				)
				(justify right)
			)
		)
		(property "Voltage" "50V"
			(at 195.58 10.16 0)
			(effects
				(font
					(size 1.27 1.27)
				)
				(justify left bottom)
				(hide yes)
			)
		)
		(property "Dielectric" "X5R"
			(at 198.12 10.16 0)
			(effects
				(font
					(size 1.27 1.27)
				)
				(justify left bottom)
				(hide yes)
			)
		)
		(property "Public" "False"
			(at 200.66 10.16 0)
			(effects
				(font
					(size 1.27 1.27)
				)
				(justify left bottom)
				(hide yes)
			)
		)
		(pin "1"
		)
		(pin "2"
		)
		(instances
			(project "com-express-7-baseboard"
				(path ""
					(reference "C127")
					(unit 1)
				)
			)
		)
	)
	(symbol
		(lib_id "antmicropower:GND")
		(at 229.87 96.52 0)
		(unit 1)
		(exclude_from_sim no)
		(in_bom yes)
		(on_board yes)
		(dnp no)
		(property "Reference" "#PWR0319"
			(at 238.76 99.06 0)
			(effects
				(font
					(size 1.27 1.27)
					(thickness 0.15)
				)
				(justify left bottom)
				(hide yes)
			)
		)
		(property "Value" "GND"
			(at 229.87 100.33 0)
			(effects
				(font
					(size 1.27 1.27)
					(thickness 0.15)
				)
			)
		)
		(property "Footprint" ""
			(at 238.76 104.14 0)
			(effects
				(font
					(size 1.27 1.27)
					(thickness 0.15)
				)
				(justify left bottom)
				(hide yes)
			)
		)
		(property "Datasheet" ""
			(at 238.76 109.22 0)
			(effects
				(font
					(size 1.27 1.27)
					(thickness 0.15)
				)
				(justify left bottom)
				(hide yes)
			)
		)
		(property "Description" ""
			(at 229.87 96.52 0)
			(effects
				(font
					(size 1.27 1.27)
				)
				(hide yes)
			)
		)
		(property "Author" "Antmicro"
			(at 238.76 104.14 0)
			(effects
				(font
					(size 1.27 1.27)
					(thickness 0.15)
				)
				(justify left bottom)
				(hide yes)
			)
		)
		(property "License" "Apache-2.0"
			(at 238.76 106.68 0)
			(effects
				(font
					(size 1.27 1.27)
					(thickness 0.15)
				)
				(justify left bottom)
				(hide yes)
			)
		)
		(pin "1"
		)
		(instances
			(project "com-express-7-baseboard"
				(path ""
					(reference "#PWR0319")
					(unit 1)
				)
			)
		)
	)
	(symbol
		(lib_id "antmicroResistors0402:R_0R_0402")
		(at 229.87 96.52 90)
		(unit 1)
		(exclude_from_sim no)
		(in_bom yes)
		(on_board yes)
		(dnp yes)
		(property "Reference" "R218"
			(at 231.14 92.71 90)
			(effects
				(font
					(size 1.27 1.27)
					(thickness 0.15)
				)
				(justify right)
			)
		)
		(property "Value" "R_0R_0402"
			(at 242.57 76.2 0)
			(effects
				(font
					(size 1.27 1.27)
					(thickness 0.15)
				)
				(justify left bottom)
				(hide yes)
			)
		)
		(property "Footprint" "antmicro-footprints:R_0402_1005Metric"
			(at 245.11 76.2 0)
			(effects
				(font
					(size 1.27 1.27)
					(thickness 0.15)
				)
				(justify left bottom)
				(hide yes)
			)
		)
		(property "Datasheet" "https://industrial.panasonic.com/cdbs/www-data/pdf/RDA0000/AOA0000C301.pdf"
			(at 247.65 76.2 0)
			(effects
				(font
					(size 1.27 1.27)
					(thickness 0.15)
				)
				(justify left bottom)
				(hide yes)
			)
		)
		(property "Description" ""
			(at 229.87 96.52 0)
			(effects
				(font
					(size 1.27 1.27)
				)
				(hide yes)
			)
		)
		(property "MPN" "ERJ2GE0R00X"
			(at 250.19 76.2 0)
			(effects
				(font
					(size 1.27 1.27)
					(thickness 0.15)
				)
				(justify left bottom)
				(hide yes)
			)
		)
		(property "Manufacturer" "Panasonic"
			(at 252.73 76.2 0)
			(effects
				(font
					(size 1.27 1.27)
					(thickness 0.15)
				)
				(justify left bottom)
				(hide yes)
			)
		)
		(property "License" "Apache-2.0"
			(at 255.27 76.2 0)
			(effects
				(font
					(size 1.27 1.27)
					(thickness 0.15)
				)
				(justify left bottom)
				(hide yes)
			)
		)
		(property "Author" "Antmicro"
			(at 257.81 76.2 0)
			(effects
				(font
					(size 1.27 1.27)
					(thickness 0.15)
				)
				(justify left bottom)
				(hide yes)
			)
		)
		(property "Val" "0R"
			(at 231.14 95.25 90)
			(effects
				(font
					(size 1.27 1.27)
					(thickness 0.15)
				)
				(justify right)
			)
		)
		(property "Tolerance" "~"
			(at 240.03 76.2 0)
			(effects
				(font
					(size 1.27 1.27)
				)
				(justify left bottom)
				(hide yes)
			)
		)
		(property "Current" "1A"
			(at 260.35 76.2 0)
			(effects
				(font
					(size 1.27 1.27)
					(thickness 0.15)
				)
				(justify left bottom)
				(hide yes)
			)
		)
		(property "Public" "False"
			(at 260.35 76.2 0)
			(effects
				(font
					(size 1.27 1.27)
				)
				(justify left bottom)
				(hide yes)
			)
		)
		(pin "1"
		)
		(pin "2"
		)
		(instances
			(project "com-express-7-baseboard"
				(path ""
					(reference "R218")
					(unit 1)
				)
			)
		)
	)
	(symbol
		(lib_id "antmicroCapacitors0402:C_100n_0402")
		(at 170.18 152.4 90)
		(unit 1)
		(exclude_from_sim no)
		(in_bom yes)
		(on_board yes)
		(dnp no)
		(fields_autoplaced yes)
		(property "Reference" "C133"
			(at 172.72 148.5836 90)
			(effects
				(font
					(size 1.27 1.27)
					(thickness 0.15)
				)
				(justify right)
			)
		)
		(property "Value" "C_100n_0402"
			(at 180.34 132.08 0)
			(effects
				(font
					(size 1.27 1.27)
					(thickness 0.15)
				)
				(justify left bottom)
				(hide yes)
			)
		)
		(property "Footprint" "antmicro-footprints:C_0402_1005Metric"
			(at 182.88 132.08 0)
			(effects
				(font
					(size 1.27 1.27)
					(thickness 0.15)
				)
				(justify left bottom)
				(hide yes)
			)
		)
		(property "Datasheet" "https://www.murata.com/products/productdetail?partno=GRM155R61H104KE14%23"
			(at 185.42 132.08 0)
			(effects
				(font
					(size 1.27 1.27)
					(thickness 0.15)
				)
				(justify left bottom)
				(hide yes)
			)
		)
		(property "Description" ""
			(at 170.18 152.4 0)
			(effects
				(font
					(size 1.27 1.27)
				)
				(hide yes)
			)
		)
		(property "MPN" "GRM155R61H104KE14D"
			(at 187.96 132.08 0)
			(effects
				(font
					(size 1.27 1.27)
					(thickness 0.15)
				)
				(justify left bottom)
				(hide yes)
			)
		)
		(property "Manufacturer" "Murata"
			(at 190.5 132.08 0)
			(effects
				(font
					(size 1.27 1.27)
					(thickness 0.15)
				)
				(justify left bottom)
				(hide yes)
			)
		)
		(property "License" "Apache-2.0"
			(at 193.04 132.08 0)
			(effects
				(font
					(size 1.27 1.27)
					(thickness 0.15)
				)
				(justify left bottom)
				(hide yes)
			)
		)
		(property "Author" "Antmicro"
			(at 195.58 132.08 0)
			(effects
				(font
					(size 1.27 1.27)
					(thickness 0.15)
				)
				(justify left bottom)
				(hide yes)
			)
		)
		(property "Val" "100n"
			(at 172.72 151.1236 90)
			(effects
				(font
					(size 1.27 1.27)
					(thickness 0.15)
				)
				(justify right)
			)
		)
		(property "Voltage" "50V"
			(at 198.12 132.08 0)
			(effects
				(font
					(size 1.27 1.27)
				)
				(justify left bottom)
				(hide yes)
			)
		)
		(property "Dielectric" "X5R"
			(at 200.66 132.08 0)
			(effects
				(font
					(size 1.27 1.27)
				)
				(justify left bottom)
				(hide yes)
			)
		)
		(property "Public" "False"
			(at 203.2 132.08 0)
			(effects
				(font
					(size 1.27 1.27)
				)
				(justify left bottom)
				(hide yes)
			)
		)
		(pin "1"
		)
		(pin "2"
		)
		(instances
			(project "com-express-7-baseboard"
				(path ""
					(reference "C133")
					(unit 1)
				)
			)
		)
	)
	(symbol
		(lib_id "antmicroCapacitors0402:C_220n_0402")
		(at 152.4 194.31 0)
		(unit 1)
		(exclude_from_sim no)
		(in_bom yes)
		(on_board yes)
		(dnp no)
		(property "Reference" "C124"
			(at 151.13 195.58 0)
			(effects
				(font
					(size 1.27 1.27)
					(thickness 0.15)
				)
			)
		)
		(property "Value" "C_220n_0402"
			(at 172.72 204.47 0)
			(effects
				(font
					(size 1.27 1.27)
					(thickness 0.15)
				)
				(justify left bottom)
				(hide yes)
			)
		)
		(property "Footprint" "antmicro-footprints:C_0402_1005Metric"
			(at 172.72 207.01 0)
			(effects
				(font
					(size 1.27 1.27)
					(thickness 0.15)
				)
				(justify left bottom)
				(hide yes)
			)
		)
		(property "Datasheet" "https://www.yageo.com/en/Chart/Download/pdf/CC0402KRX5R6BB224"
			(at 172.72 209.55 0)
			(effects
				(font
					(size 1.27 1.27)
					(thickness 0.15)
				)
				(justify left bottom)
				(hide yes)
			)
		)
		(property "Description" ""
			(at 152.4 194.31 0)
			(effects
				(font
					(size 1.27 1.27)
				)
				(hide yes)
			)
		)
		(property "MPN" "CC0402KRX5R6BB224"
			(at 172.72 212.09 0)
			(effects
				(font
					(size 1.27 1.27)
					(thickness 0.15)
				)
				(justify left bottom)
				(hide yes)
			)
		)
		(property "Manufacturer" "YAGEO"
			(at 172.72 214.63 0)
			(effects
				(font
					(size 1.27 1.27)
					(thickness 0.15)
				)
				(justify left bottom)
				(hide yes)
			)
		)
		(property "License" "Apache-2.0"
			(at 172.72 217.17 0)
			(effects
				(font
					(size 1.27 1.27)
					(thickness 0.15)
				)
				(justify left bottom)
				(hide yes)
			)
		)
		(property "Author" "Antmicro"
			(at 172.72 219.71 0)
			(effects
				(font
					(size 1.27 1.27)
					(thickness 0.15)
				)
				(justify left bottom)
				(hide yes)
			)
		)
		(property "Val" "220n"
			(at 158.75 195.58 0)
			(effects
				(font
					(size 1.27 1.27)
					(thickness 0.15)
				)
			)
		)
		(property "Voltage" ""
			(at 172.72 222.25 0)
			(effects
				(font
					(size 1.27 1.27)
				)
				(justify left bottom)
				(hide yes)
			)
		)
		(property "Dielectric" ""
			(at 172.72 224.79 0)
			(effects
				(font
					(size 1.27 1.27)
				)
				(justify left bottom)
				(hide yes)
			)
		)
		(property "Public" "False"
			(at 172.72 227.33 0)
			(effects
				(font
					(size 1.27 1.27)
				)
				(justify left bottom)
				(hide yes)
			)
		)
		(pin "1"
		)
		(pin "2"
		)
		(instances
			(project "com-express-7-baseboard"
				(path ""
					(reference "C124")
					(unit 1)
				)
			)
		)
	)
	(symbol
		(lib_id "antmicroCapacitors0402:C_100n_0402")
		(at 161.29 167.64 90)
		(unit 1)
		(exclude_from_sim no)
		(in_bom yes)
		(on_board yes)
		(dnp no)
		(fields_autoplaced yes)
		(property "Reference" "C122"
			(at 163.83 163.8236 90)
			(effects
				(font
					(size 1.27 1.27)
					(thickness 0.15)
				)
				(justify right)
			)
		)
		(property "Value" "C_100n_0402"
			(at 171.45 147.32 0)
			(effects
				(font
					(size 1.27 1.27)
					(thickness 0.15)
				)
				(justify left bottom)
				(hide yes)
			)
		)
		(property "Footprint" "antmicro-footprints:C_0402_1005Metric"
			(at 173.99 147.32 0)
			(effects
				(font
					(size 1.27 1.27)
					(thickness 0.15)
				)
				(justify left bottom)
				(hide yes)
			)
		)
		(property "Datasheet" "https://www.murata.com/products/productdetail?partno=GRM155R61H104KE14%23"
			(at 176.53 147.32 0)
			(effects
				(font
					(size 1.27 1.27)
					(thickness 0.15)
				)
				(justify left bottom)
				(hide yes)
			)
		)
		(property "Description" ""
			(at 161.29 167.64 0)
			(effects
				(font
					(size 1.27 1.27)
				)
				(hide yes)
			)
		)
		(property "MPN" "GRM155R61H104KE14D"
			(at 179.07 147.32 0)
			(effects
				(font
					(size 1.27 1.27)
					(thickness 0.15)
				)
				(justify left bottom)
				(hide yes)
			)
		)
		(property "Manufacturer" "Murata"
			(at 181.61 147.32 0)
			(effects
				(font
					(size 1.27 1.27)
					(thickness 0.15)
				)
				(justify left bottom)
				(hide yes)
			)
		)
		(property "License" "Apache-2.0"
			(at 184.15 147.32 0)
			(effects
				(font
					(size 1.27 1.27)
					(thickness 0.15)
				)
				(justify left bottom)
				(hide yes)
			)
		)
		(property "Author" "Antmicro"
			(at 186.69 147.32 0)
			(effects
				(font
					(size 1.27 1.27)
					(thickness 0.15)
				)
				(justify left bottom)
				(hide yes)
			)
		)
		(property "Val" "100n"
			(at 163.83 166.3636 90)
			(effects
				(font
					(size 1.27 1.27)
					(thickness 0.15)
				)
				(justify right)
			)
		)
		(property "Voltage" "50V"
			(at 189.23 147.32 0)
			(effects
				(font
					(size 1.27 1.27)
				)
				(justify left bottom)
				(hide yes)
			)
		)
		(property "Dielectric" "X5R"
			(at 191.77 147.32 0)
			(effects
				(font
					(size 1.27 1.27)
				)
				(justify left bottom)
				(hide yes)
			)
		)
		(property "Public" "False"
			(at 194.31 147.32 0)
			(effects
				(font
					(size 1.27 1.27)
				)
				(justify left bottom)
				(hide yes)
			)
		)
		(pin "1"
		)
		(pin "2"
		)
		(instances
			(project "com-express-7-baseboard"
				(path ""
					(reference "C122")
					(unit 1)
				)
			)
		)
	)
	(symbol
		(lib_id "antmicroResistors0402:R_1k_0402")
		(at 156.21 127 90)
		(unit 1)
		(exclude_from_sim no)
		(in_bom yes)
		(on_board yes)
		(dnp yes)
		(property "Reference" "R211"
			(at 156.21 130.81 0)
			(effects
				(font
					(size 1.27 1.27)
					(thickness 0.15)
				)
				(justify right)
			)
		)
		(property "Value" "R_1k_0402"
			(at 168.91 106.68 0)
			(effects
				(font
					(size 1.27 1.27)
					(thickness 0.15)
				)
				(justify left bottom)
				(hide yes)
			)
		)
		(property "Footprint" "antmicro-footprints:R_0402_1005Metric"
			(at 171.45 106.68 0)
			(effects
				(font
					(size 1.27 1.27)
					(thickness 0.15)
				)
				(justify left bottom)
				(hide yes)
			)
		)
		(property "Datasheet" "https://www.bourns.com/docs/product-datasheets/cr.pdf"
			(at 173.99 106.68 0)
			(effects
				(font
					(size 1.27 1.27)
					(thickness 0.15)
				)
				(justify left bottom)
				(hide yes)
			)
		)
		(property "Description" ""
			(at 156.21 127 0)
			(effects
				(font
					(size 1.27 1.27)
				)
				(hide yes)
			)
		)
		(property "MPN" "CR0402-FX-1001GLF"
			(at 176.53 106.68 0)
			(effects
				(font
					(size 1.27 1.27)
					(thickness 0.15)
				)
				(justify left bottom)
				(hide yes)
			)
		)
		(property "Manufacturer" "Bourns"
			(at 179.07 106.68 0)
			(effects
				(font
					(size 1.27 1.27)
					(thickness 0.15)
				)
				(justify left bottom)
				(hide yes)
			)
		)
		(property "License" "Apache-2.0"
			(at 181.61 106.68 0)
			(effects
				(font
					(size 1.27 1.27)
					(thickness 0.15)
				)
				(justify left bottom)
				(hide yes)
			)
		)
		(property "Author" "Antmicro"
			(at 184.15 106.68 0)
			(effects
				(font
					(size 1.27 1.27)
					(thickness 0.15)
				)
				(justify left bottom)
				(hide yes)
			)
		)
		(property "Val" "1k"
			(at 154.94 127 0)
			(effects
				(font
					(size 1.27 1.27)
					(thickness 0.15)
				)
				(justify right)
			)
		)
		(property "Tolerance" "1%"
			(at 166.37 106.68 0)
			(effects
				(font
					(size 1.27 1.27)
				)
				(justify left bottom)
				(hide yes)
			)
		)
		(property "Public" "False"
			(at 186.69 106.68 0)
			(effects
				(font
					(size 1.27 1.27)
				)
				(justify left bottom)
				(hide yes)
			)
		)
		(pin "1"
		)
		(pin "2"
		)
		(instances
			(project "com-express-7-baseboard"
				(path ""
					(reference "R211")
					(unit 1)
				)
			)
		)
	)
	(symbol
		(lib_id "antmicroCapacitors0402:C_220n_0402")
		(at 232.41 74.93 0)
		(unit 1)
		(exclude_from_sim no)
		(in_bom yes)
		(on_board yes)
		(dnp no)
		(property "Reference" "C145"
			(at 231.14 73.66 0)
			(effects
				(font
					(size 1.27 1.27)
					(thickness 0.15)
				)
			)
		)
		(property "Value" "C_220n_0402"
			(at 252.73 85.09 0)
			(effects
				(font
					(size 1.27 1.27)
					(thickness 0.15)
				)
				(justify left bottom)
				(hide yes)
			)
		)
		(property "Footprint" "antmicro-footprints:C_0402_1005Metric"
			(at 252.73 87.63 0)
			(effects
				(font
					(size 1.27 1.27)
					(thickness 0.15)
				)
				(justify left bottom)
				(hide yes)
			)
		)
		(property "Datasheet" "https://www.yageo.com/en/Chart/Download/pdf/CC0402KRX5R6BB224"
			(at 252.73 90.17 0)
			(effects
				(font
					(size 1.27 1.27)
					(thickness 0.15)
				)
				(justify left bottom)
				(hide yes)
			)
		)
		(property "Description" ""
			(at 232.41 74.93 0)
			(effects
				(font
					(size 1.27 1.27)
				)
				(hide yes)
			)
		)
		(property "MPN" "CC0402KRX5R6BB224"
			(at 252.73 92.71 0)
			(effects
				(font
					(size 1.27 1.27)
					(thickness 0.15)
				)
				(justify left bottom)
				(hide yes)
			)
		)
		(property "Manufacturer" "YAGEO"
			(at 252.73 95.25 0)
			(effects
				(font
					(size 1.27 1.27)
					(thickness 0.15)
				)
				(justify left bottom)
				(hide yes)
			)
		)
		(property "License" "Apache-2.0"
			(at 252.73 97.79 0)
			(effects
				(font
					(size 1.27 1.27)
					(thickness 0.15)
				)
				(justify left bottom)
				(hide yes)
			)
		)
		(property "Author" "Antmicro"
			(at 252.73 100.33 0)
			(effects
				(font
					(size 1.27 1.27)
					(thickness 0.15)
				)
				(justify left bottom)
				(hide yes)
			)
		)
		(property "Val" "220n"
			(at 238.76 73.66 0)
			(effects
				(font
					(size 1.27 1.27)
					(thickness 0.15)
				)
			)
		)
		(property "Voltage" ""
			(at 252.73 102.87 0)
			(effects
				(font
					(size 1.27 1.27)
				)
				(justify left bottom)
				(hide yes)
			)
		)
		(property "Dielectric" ""
			(at 252.73 105.41 0)
			(effects
				(font
					(size 1.27 1.27)
				)
				(justify left bottom)
				(hide yes)
			)
		)
		(property "Public" "False"
			(at 252.73 107.95 0)
			(effects
				(font
					(size 1.27 1.27)
				)
				(justify left bottom)
				(hide yes)
			)
		)
		(pin "1"
		)
		(pin "2"
		)
		(instances
			(project "com-express-7-baseboard"
				(path ""
					(reference "C145")
					(unit 1)
				)
			)
		)
	)
	(symbol
		(lib_id "antmicroCapacitors0402:C_100n_0402")
		(at 152.4 152.4 90)
		(unit 1)
		(exclude_from_sim no)
		(in_bom yes)
		(on_board yes)
		(dnp no)
		(fields_autoplaced yes)
		(property "Reference" "C117"
			(at 154.94 148.5836 90)
			(effects
				(font
					(size 1.27 1.27)
					(thickness 0.15)
				)
				(justify right)
			)
		)
		(property "Value" "C_100n_0402"
			(at 162.56 132.08 0)
			(effects
				(font
					(size 1.27 1.27)
					(thickness 0.15)
				)
				(justify left bottom)
				(hide yes)
			)
		)
		(property "Footprint" "antmicro-footprints:C_0402_1005Metric"
			(at 165.1 132.08 0)
			(effects
				(font
					(size 1.27 1.27)
					(thickness 0.15)
				)
				(justify left bottom)
				(hide yes)
			)
		)
		(property "Datasheet" "https://www.murata.com/products/productdetail?partno=GRM155R61H104KE14%23"
			(at 167.64 132.08 0)
			(effects
				(font
					(size 1.27 1.27)
					(thickness 0.15)
				)
				(justify left bottom)
				(hide yes)
			)
		)
		(property "Description" ""
			(at 152.4 152.4 0)
			(effects
				(font
					(size 1.27 1.27)
				)
				(hide yes)
			)
		)
		(property "MPN" "GRM155R61H104KE14D"
			(at 170.18 132.08 0)
			(effects
				(font
					(size 1.27 1.27)
					(thickness 0.15)
				)
				(justify left bottom)
				(hide yes)
			)
		)
		(property "Manufacturer" "Murata"
			(at 172.72 132.08 0)
			(effects
				(font
					(size 1.27 1.27)
					(thickness 0.15)
				)
				(justify left bottom)
				(hide yes)
			)
		)
		(property "License" "Apache-2.0"
			(at 175.26 132.08 0)
			(effects
				(font
					(size 1.27 1.27)
					(thickness 0.15)
				)
				(justify left bottom)
				(hide yes)
			)
		)
		(property "Author" "Antmicro"
			(at 177.8 132.08 0)
			(effects
				(font
					(size 1.27 1.27)
					(thickness 0.15)
				)
				(justify left bottom)
				(hide yes)
			)
		)
		(property "Val" "100n"
			(at 154.94 151.1236 90)
			(effects
				(font
					(size 1.27 1.27)
					(thickness 0.15)
				)
				(justify right)
			)
		)
		(property "Voltage" "50V"
			(at 180.34 132.08 0)
			(effects
				(font
					(size 1.27 1.27)
				)
				(justify left bottom)
				(hide yes)
			)
		)
		(property "Dielectric" "X5R"
			(at 182.88 132.08 0)
			(effects
				(font
					(size 1.27 1.27)
				)
				(justify left bottom)
				(hide yes)
			)
		)
		(property "Public" "False"
			(at 185.42 132.08 0)
			(effects
				(font
					(size 1.27 1.27)
				)
				(justify left bottom)
				(hide yes)
			)
		)
		(pin "1"
		)
		(pin "2"
		)
		(instances
			(project "com-express-7-baseboard"
				(path ""
					(reference "C117")
					(unit 1)
				)
			)
		)
	)
	(symbol
		(lib_id "antmicroCapacitors0402:C_100n_0402")
		(at 158.75 45.72 90)
		(unit 1)
		(exclude_from_sim no)
		(in_bom yes)
		(on_board yes)
		(dnp no)
		(fields_autoplaced yes)
		(property "Reference" "C120"
			(at 161.29 41.9036 90)
			(effects
				(font
					(size 1.27 1.27)
					(thickness 0.15)
				)
				(justify right)
			)
		)
		(property "Value" "C_100n_0402"
			(at 168.91 25.4 0)
			(effects
				(font
					(size 1.27 1.27)
					(thickness 0.15)
				)
				(justify left bottom)
				(hide yes)
			)
		)
		(property "Footprint" "antmicro-footprints:C_0402_1005Metric"
			(at 171.45 25.4 0)
			(effects
				(font
					(size 1.27 1.27)
					(thickness 0.15)
				)
				(justify left bottom)
				(hide yes)
			)
		)
		(property "Datasheet" "https://www.murata.com/products/productdetail?partno=GRM155R61H104KE14%23"
			(at 173.99 25.4 0)
			(effects
				(font
					(size 1.27 1.27)
					(thickness 0.15)
				)
				(justify left bottom)
				(hide yes)
			)
		)
		(property "Description" ""
			(at 158.75 45.72 0)
			(effects
				(font
					(size 1.27 1.27)
				)
				(hide yes)
			)
		)
		(property "MPN" "GRM155R61H104KE14D"
			(at 176.53 25.4 0)
			(effects
				(font
					(size 1.27 1.27)
					(thickness 0.15)
				)
				(justify left bottom)
				(hide yes)
			)
		)
		(property "Manufacturer" "Murata"
			(at 179.07 25.4 0)
			(effects
				(font
					(size 1.27 1.27)
					(thickness 0.15)
				)
				(justify left bottom)
				(hide yes)
			)
		)
		(property "License" "Apache-2.0"
			(at 181.61 25.4 0)
			(effects
				(font
					(size 1.27 1.27)
					(thickness 0.15)
				)
				(justify left bottom)
				(hide yes)
			)
		)
		(property "Author" "Antmicro"
			(at 184.15 25.4 0)
			(effects
				(font
					(size 1.27 1.27)
					(thickness 0.15)
				)
				(justify left bottom)
				(hide yes)
			)
		)
		(property "Val" "100n"
			(at 161.29 44.4436 90)
			(effects
				(font
					(size 1.27 1.27)
					(thickness 0.15)
				)
				(justify right)
			)
		)
		(property "Voltage" "50V"
			(at 186.69 25.4 0)
			(effects
				(font
					(size 1.27 1.27)
				)
				(justify left bottom)
				(hide yes)
			)
		)
		(property "Dielectric" "X5R"
			(at 189.23 25.4 0)
			(effects
				(font
					(size 1.27 1.27)
				)
				(justify left bottom)
				(hide yes)
			)
		)
		(property "Public" "False"
			(at 191.77 25.4 0)
			(effects
				(font
					(size 1.27 1.27)
				)
				(justify left bottom)
				(hide yes)
			)
		)
		(pin "1"
		)
		(pin "2"
		)
		(instances
			(project "com-express-7-baseboard"
				(path ""
					(reference "C120")
					(unit 1)
				)
			)
		)
	)
	(symbol
		(lib_id "antmicropower:GND")
		(at 250.19 256.54 0)
		(mirror y)
		(unit 1)
		(exclude_from_sim no)
		(in_bom yes)
		(on_board yes)
		(dnp no)
		(property "Reference" "#PWR0321"
			(at 241.3 259.08 0)
			(effects
				(font
					(size 1.27 1.27)
					(thickness 0.15)
				)
				(justify left bottom)
				(hide yes)
			)
		)
		(property "Value" "GND"
			(at 250.19 260.35 0)
			(effects
				(font
					(size 1.27 1.27)
					(thickness 0.15)
				)
			)
		)
		(property "Footprint" ""
			(at 241.3 264.16 0)
			(effects
				(font
					(size 1.27 1.27)
					(thickness 0.15)
				)
				(justify left bottom)
				(hide yes)
			)
		)
		(property "Datasheet" ""
			(at 241.3 269.24 0)
			(effects
				(font
					(size 1.27 1.27)
					(thickness 0.15)
				)
				(justify left bottom)
				(hide yes)
			)
		)
		(property "Description" ""
			(at 250.19 256.54 0)
			(effects
				(font
					(size 1.27 1.27)
				)
				(hide yes)
			)
		)
		(property "Author" "Antmicro"
			(at 241.3 264.16 0)
			(effects
				(font
					(size 1.27 1.27)
					(thickness 0.15)
				)
				(justify left bottom)
				(hide yes)
			)
		)
		(property "License" "Apache-2.0"
			(at 241.3 266.7 0)
			(effects
				(font
					(size 1.27 1.27)
					(thickness 0.15)
				)
				(justify left bottom)
				(hide yes)
			)
		)
		(pin "1"
		)
		(instances
			(project "com-express-7-baseboard"
				(path ""
					(reference "#PWR0321")
					(unit 1)
				)
			)
		)
	)
	(symbol
		(lib_id "antmicropower:GND")
		(at 132.08 30.48 0)
		(unit 1)
		(exclude_from_sim no)
		(in_bom yes)
		(on_board yes)
		(dnp no)
		(property "Reference" "#PWR0290"
			(at 140.97 33.02 0)
			(effects
				(font
					(size 1.27 1.27)
					(thickness 0.15)
				)
				(justify left bottom)
				(hide yes)
			)
		)
		(property "Value" "GND"
			(at 132.08 34.29 0)
			(effects
				(font
					(size 1.27 1.27)
					(thickness 0.15)
				)
			)
		)
		(property "Footprint" ""
			(at 140.97 38.1 0)
			(effects
				(font
					(size 1.27 1.27)
					(thickness 0.15)
				)
				(justify left bottom)
				(hide yes)
			)
		)
		(property "Datasheet" ""
			(at 140.97 43.18 0)
			(effects
				(font
					(size 1.27 1.27)
					(thickness 0.15)
				)
				(justify left bottom)
				(hide yes)
			)
		)
		(property "Description" ""
			(at 132.08 30.48 0)
			(effects
				(font
					(size 1.27 1.27)
				)
				(hide yes)
			)
		)
		(property "Author" "Antmicro"
			(at 140.97 38.1 0)
			(effects
				(font
					(size 1.27 1.27)
					(thickness 0.15)
				)
				(justify left bottom)
				(hide yes)
			)
		)
		(property "License" "Apache-2.0"
			(at 140.97 40.64 0)
			(effects
				(font
					(size 1.27 1.27)
					(thickness 0.15)
				)
				(justify left bottom)
				(hide yes)
			)
		)
		(pin "1"
		)
		(instances
			(project "com-express-7-baseboard"
				(path ""
					(reference "#PWR0290")
					(unit 1)
				)
			)
		)
	)
	(symbol
		(lib_id "antmicroResistors0402:R_1k_0402")
		(at 237.49 222.25 90)
		(mirror x)
		(unit 1)
		(exclude_from_sim no)
		(in_bom yes)
		(on_board yes)
		(dnp no)
		(property "Reference" "R221"
			(at 237.49 218.44 0)
			(effects
				(font
					(size 1.27 1.27)
					(thickness 0.15)
				)
				(justify right)
			)
		)
		(property "Value" "R_1k_0402"
			(at 250.19 242.57 0)
			(effects
				(font
					(size 1.27 1.27)
					(thickness 0.15)
				)
				(justify left bottom)
				(hide yes)
			)
		)
		(property "Footprint" "antmicro-footprints:R_0402_1005Metric"
			(at 252.73 242.57 0)
			(effects
				(font
					(size 1.27 1.27)
					(thickness 0.15)
				)
				(justify left bottom)
				(hide yes)
			)
		)
		(property "Datasheet" "https://www.bourns.com/docs/product-datasheets/cr.pdf"
			(at 255.27 242.57 0)
			(effects
				(font
					(size 1.27 1.27)
					(thickness 0.15)
				)
				(justify left bottom)
				(hide yes)
			)
		)
		(property "Description" ""
			(at 237.49 222.25 0)
			(effects
				(font
					(size 1.27 1.27)
				)
				(hide yes)
			)
		)
		(property "MPN" "CR0402-FX-1001GLF"
			(at 257.81 242.57 0)
			(effects
				(font
					(size 1.27 1.27)
					(thickness 0.15)
				)
				(justify left bottom)
				(hide yes)
			)
		)
		(property "Manufacturer" "Bourns"
			(at 260.35 242.57 0)
			(effects
				(font
					(size 1.27 1.27)
					(thickness 0.15)
				)
				(justify left bottom)
				(hide yes)
			)
		)
		(property "License" "Apache-2.0"
			(at 262.89 242.57 0)
			(effects
				(font
					(size 1.27 1.27)
					(thickness 0.15)
				)
				(justify left bottom)
				(hide yes)
			)
		)
		(property "Author" "Antmicro"
			(at 265.43 242.57 0)
			(effects
				(font
					(size 1.27 1.27)
					(thickness 0.15)
				)
				(justify left bottom)
				(hide yes)
			)
		)
		(property "Val" "1k"
			(at 236.22 222.25 0)
			(effects
				(font
					(size 1.27 1.27)
					(thickness 0.15)
				)
				(justify right)
			)
		)
		(property "Tolerance" "1%"
			(at 247.65 242.57 0)
			(effects
				(font
					(size 1.27 1.27)
				)
				(justify left bottom)
				(hide yes)
			)
		)
		(property "Public" "False"
			(at 267.97 242.57 0)
			(effects
				(font
					(size 1.27 1.27)
				)
				(justify left bottom)
				(hide yes)
			)
		)
		(pin "1"
		)
		(pin "2"
		)
		(instances
			(project "com-express-7-baseboard"
				(path ""
					(reference "R221")
					(unit 1)
				)
			)
		)
	)
	(symbol
		(lib_id "antmicroCapacitors0402:C_100n_0402")
		(at 149.86 45.72 90)
		(unit 1)
		(exclude_from_sim no)
		(in_bom yes)
		(on_board yes)
		(dnp no)
		(fields_autoplaced yes)
		(property "Reference" "C116"
			(at 152.4 41.9036 90)
			(effects
				(font
					(size 1.27 1.27)
					(thickness 0.15)
				)
				(justify right)
			)
		)
		(property "Value" "C_100n_0402"
			(at 160.02 25.4 0)
			(effects
				(font
					(size 1.27 1.27)
					(thickness 0.15)
				)
				(justify left bottom)
				(hide yes)
			)
		)
		(property "Footprint" "antmicro-footprints:C_0402_1005Metric"
			(at 162.56 25.4 0)
			(effects
				(font
					(size 1.27 1.27)
					(thickness 0.15)
				)
				(justify left bottom)
				(hide yes)
			)
		)
		(property "Datasheet" "https://www.murata.com/products/productdetail?partno=GRM155R61H104KE14%23"
			(at 165.1 25.4 0)
			(effects
				(font
					(size 1.27 1.27)
					(thickness 0.15)
				)
				(justify left bottom)
				(hide yes)
			)
		)
		(property "Description" ""
			(at 149.86 45.72 0)
			(effects
				(font
					(size 1.27 1.27)
				)
				(hide yes)
			)
		)
		(property "MPN" "GRM155R61H104KE14D"
			(at 167.64 25.4 0)
			(effects
				(font
					(size 1.27 1.27)
					(thickness 0.15)
				)
				(justify left bottom)
				(hide yes)
			)
		)
		(property "Manufacturer" "Murata"
			(at 170.18 25.4 0)
			(effects
				(font
					(size 1.27 1.27)
					(thickness 0.15)
				)
				(justify left bottom)
				(hide yes)
			)
		)
		(property "License" "Apache-2.0"
			(at 172.72 25.4 0)
			(effects
				(font
					(size 1.27 1.27)
					(thickness 0.15)
				)
				(justify left bottom)
				(hide yes)
			)
		)
		(property "Author" "Antmicro"
			(at 175.26 25.4 0)
			(effects
				(font
					(size 1.27 1.27)
					(thickness 0.15)
				)
				(justify left bottom)
				(hide yes)
			)
		)
		(property "Val" "100n"
			(at 152.4 44.4436 90)
			(effects
				(font
					(size 1.27 1.27)
					(thickness 0.15)
				)
				(justify right)
			)
		)
		(property "Voltage" "50V"
			(at 177.8 25.4 0)
			(effects
				(font
					(size 1.27 1.27)
				)
				(justify left bottom)
				(hide yes)
			)
		)
		(property "Dielectric" "X5R"
			(at 180.34 25.4 0)
			(effects
				(font
					(size 1.27 1.27)
				)
				(justify left bottom)
				(hide yes)
			)
		)
		(property "Public" "False"
			(at 182.88 25.4 0)
			(effects
				(font
					(size 1.27 1.27)
				)
				(justify left bottom)
				(hide yes)
			)
		)
		(pin "1"
		)
		(pin "2"
		)
		(instances
			(project "com-express-7-baseboard"
				(path ""
					(reference "C116")
					(unit 1)
				)
			)
		)
	)
	(symbol
		(lib_id "antmicroCapacitors0402:C_100n_0402")
		(at 187.96 152.4 90)
		(unit 1)
		(exclude_from_sim no)
		(in_bom yes)
		(on_board yes)
		(dnp no)
		(fields_autoplaced yes)
		(property "Reference" "C137"
			(at 190.5 148.5836 90)
			(effects
				(font
					(size 1.27 1.27)
					(thickness 0.15)
				)
				(justify right)
			)
		)
		(property "Value" "C_100n_0402"
			(at 198.12 132.08 0)
			(effects
				(font
					(size 1.27 1.27)
					(thickness 0.15)
				)
				(justify left bottom)
				(hide yes)
			)
		)
		(property "Footprint" "antmicro-footprints:C_0402_1005Metric"
			(at 200.66 132.08 0)
			(effects
				(font
					(size 1.27 1.27)
					(thickness 0.15)
				)
				(justify left bottom)
				(hide yes)
			)
		)
		(property "Datasheet" "https://www.murata.com/products/productdetail?partno=GRM155R61H104KE14%23"
			(at 203.2 132.08 0)
			(effects
				(font
					(size 1.27 1.27)
					(thickness 0.15)
				)
				(justify left bottom)
				(hide yes)
			)
		)
		(property "Description" ""
			(at 187.96 152.4 0)
			(effects
				(font
					(size 1.27 1.27)
				)
				(hide yes)
			)
		)
		(property "MPN" "GRM155R61H104KE14D"
			(at 205.74 132.08 0)
			(effects
				(font
					(size 1.27 1.27)
					(thickness 0.15)
				)
				(justify left bottom)
				(hide yes)
			)
		)
		(property "Manufacturer" "Murata"
			(at 208.28 132.08 0)
			(effects
				(font
					(size 1.27 1.27)
					(thickness 0.15)
				)
				(justify left bottom)
				(hide yes)
			)
		)
		(property "License" "Apache-2.0"
			(at 210.82 132.08 0)
			(effects
				(font
					(size 1.27 1.27)
					(thickness 0.15)
				)
				(justify left bottom)
				(hide yes)
			)
		)
		(property "Author" "Antmicro"
			(at 213.36 132.08 0)
			(effects
				(font
					(size 1.27 1.27)
					(thickness 0.15)
				)
				(justify left bottom)
				(hide yes)
			)
		)
		(property "Val" "100n"
			(at 190.5 151.1236 90)
			(effects
				(font
					(size 1.27 1.27)
					(thickness 0.15)
				)
				(justify right)
			)
		)
		(property "Voltage" "50V"
			(at 215.9 132.08 0)
			(effects
				(font
					(size 1.27 1.27)
				)
				(justify left bottom)
				(hide yes)
			)
		)
		(property "Dielectric" "X5R"
			(at 218.44 132.08 0)
			(effects
				(font
					(size 1.27 1.27)
				)
				(justify left bottom)
				(hide yes)
			)
		)
		(property "Public" "False"
			(at 220.98 132.08 0)
			(effects
				(font
					(size 1.27 1.27)
				)
				(justify left bottom)
				(hide yes)
			)
		)
		(pin "1"
		)
		(pin "2"
		)
		(instances
			(project "com-express-7-baseboard"
				(path ""
					(reference "C137")
					(unit 1)
				)
			)
		)
	)
	(symbol
		(lib_id "antmicropower:GND")
		(at 187.96 152.4 0)
		(unit 1)
		(exclude_from_sim no)
		(in_bom yes)
		(on_board yes)
		(dnp no)
		(property "Reference" "#PWR0314"
			(at 196.85 154.94 0)
			(effects
				(font
					(size 1.27 1.27)
					(thickness 0.15)
				)
				(justify left bottom)
				(hide yes)
			)
		)
		(property "Value" "GND"
			(at 187.96 156.21 0)
			(effects
				(font
					(size 1.27 1.27)
					(thickness 0.15)
				)
			)
		)
		(property "Footprint" ""
			(at 196.85 160.02 0)
			(effects
				(font
					(size 1.27 1.27)
					(thickness 0.15)
				)
				(justify left bottom)
				(hide yes)
			)
		)
		(property "Datasheet" ""
			(at 196.85 165.1 0)
			(effects
				(font
					(size 1.27 1.27)
					(thickness 0.15)
				)
				(justify left bottom)
				(hide yes)
			)
		)
		(property "Description" ""
			(at 187.96 152.4 0)
			(effects
				(font
					(size 1.27 1.27)
				)
				(hide yes)
			)
		)
		(property "Author" "Antmicro"
			(at 196.85 160.02 0)
			(effects
				(font
					(size 1.27 1.27)
					(thickness 0.15)
				)
				(justify left bottom)
				(hide yes)
			)
		)
		(property "License" "Apache-2.0"
			(at 196.85 162.56 0)
			(effects
				(font
					(size 1.27 1.27)
					(thickness 0.15)
				)
				(justify left bottom)
				(hide yes)
			)
		)
		(pin "1"
		)
		(instances
			(project "com-express-7-baseboard"
				(path ""
					(reference "#PWR0314")
					(unit 1)
				)
			)
		)
	)
	(symbol
		(lib_id "antmicroCapacitors0402:C_100n_0402")
		(at 140.97 45.72 90)
		(unit 1)
		(exclude_from_sim no)
		(in_bom yes)
		(on_board yes)
		(dnp no)
		(fields_autoplaced yes)
		(property "Reference" "C114"
			(at 143.51 41.9036 90)
			(effects
				(font
					(size 1.27 1.27)
					(thickness 0.15)
				)
				(justify right)
			)
		)
		(property "Value" "C_100n_0402"
			(at 151.13 25.4 0)
			(effects
				(font
					(size 1.27 1.27)
					(thickness 0.15)
				)
				(justify left bottom)
				(hide yes)
			)
		)
		(property "Footprint" "antmicro-footprints:C_0402_1005Metric"
			(at 153.67 25.4 0)
			(effects
				(font
					(size 1.27 1.27)
					(thickness 0.15)
				)
				(justify left bottom)
				(hide yes)
			)
		)
		(property "Datasheet" "https://www.murata.com/products/productdetail?partno=GRM155R61H104KE14%23"
			(at 156.21 25.4 0)
			(effects
				(font
					(size 1.27 1.27)
					(thickness 0.15)
				)
				(justify left bottom)
				(hide yes)
			)
		)
		(property "Description" ""
			(at 140.97 45.72 0)
			(effects
				(font
					(size 1.27 1.27)
				)
				(hide yes)
			)
		)
		(property "MPN" "GRM155R61H104KE14D"
			(at 158.75 25.4 0)
			(effects
				(font
					(size 1.27 1.27)
					(thickness 0.15)
				)
				(justify left bottom)
				(hide yes)
			)
		)
		(property "Manufacturer" "Murata"
			(at 161.29 25.4 0)
			(effects
				(font
					(size 1.27 1.27)
					(thickness 0.15)
				)
				(justify left bottom)
				(hide yes)
			)
		)
		(property "License" "Apache-2.0"
			(at 163.83 25.4 0)
			(effects
				(font
					(size 1.27 1.27)
					(thickness 0.15)
				)
				(justify left bottom)
				(hide yes)
			)
		)
		(property "Author" "Antmicro"
			(at 166.37 25.4 0)
			(effects
				(font
					(size 1.27 1.27)
					(thickness 0.15)
				)
				(justify left bottom)
				(hide yes)
			)
		)
		(property "Val" "100n"
			(at 143.51 44.4436 90)
			(effects
				(font
					(size 1.27 1.27)
					(thickness 0.15)
				)
				(justify right)
			)
		)
		(property "Voltage" "50V"
			(at 168.91 25.4 0)
			(effects
				(font
					(size 1.27 1.27)
				)
				(justify left bottom)
				(hide yes)
			)
		)
		(property "Dielectric" "X5R"
			(at 171.45 25.4 0)
			(effects
				(font
					(size 1.27 1.27)
				)
				(justify left bottom)
				(hide yes)
			)
		)
		(property "Public" "False"
			(at 173.99 25.4 0)
			(effects
				(font
					(size 1.27 1.27)
				)
				(justify left bottom)
				(hide yes)
			)
		)
		(pin "1"
		)
		(pin "2"
		)
		(instances
			(project "com-express-7-baseboard"
				(path ""
					(reference "C114")
					(unit 1)
				)
			)
		)
	)
	(symbol
		(lib_id "antmicroInterfaceDriversReceiversTransceivers:PI3EQX16904GL")
		(at 185.42 54.61 0)
		(unit 1)
		(exclude_from_sim no)
		(in_bom yes)
		(on_board yes)
		(dnp no)
		(fields_autoplaced yes)
		(property "Reference" "U39"
			(at 196.85 46.99 0)
			(effects
				(font
					(size 1.27 1.27)
					(thickness 0.15)
				)
			)
		)
		(property "Value" "PI3EQX16904GL"
			(at 220.98 64.77 0)
			(effects
				(font
					(size 1.27 1.27)
					(thickness 0.15)
				)
				(justify left bottom)
				(hide yes)
			)
		)
		(property "Footprint" "antmicro-footprints:WQFN-42-1EP_3.5x9mm_P0.5mm"
			(at 220.98 67.31 0)
			(effects
				(font
					(size 1.27 1.27)
					(thickness 0.15)
				)
				(justify left bottom)
				(hide yes)
			)
		)
		(property "Datasheet" "https://www.diodes.com/part/view/PI3EQX16904GL"
			(at 220.98 69.85 0)
			(effects
				(font
					(size 1.27 1.27)
					(thickness 0.15)
				)
				(justify left bottom)
				(hide yes)
			)
		)
		(property "Description" ""
			(at 185.42 54.61 0)
			(effects
				(font
					(size 1.27 1.27)
				)
				(hide yes)
			)
		)
		(property "MPN" "PI3EQX16904GLZHEX"
			(at 196.85 49.53 0)
			(effects
				(font
					(size 1.27 1.27)
					(thickness 0.15)
				)
			)
		)
		(property "Manufacturer" "Diodes Incorporated"
			(at 220.98 62.23 0)
			(effects
				(font
					(size 1.27 1.27)
					(thickness 0.15)
				)
				(justify left bottom)
				(hide yes)
			)
		)
		(property "Author" "Antmicro"
			(at 220.98 72.39 0)
			(effects
				(font
					(size 1.27 1.27)
					(thickness 0.15)
				)
				(justify left bottom)
				(hide yes)
			)
		)
		(property "License" "Apache-2.0"
			(at 220.98 74.93 0)
			(effects
				(font
					(size 1.27 1.27)
					(thickness 0.15)
				)
				(justify left bottom)
				(hide yes)
			)
		)
		(pin "9"
		)
		(pin "29"
		)
		(pin "30"
		)
		(pin "4"
		)
		(pin "20"
		)
		(pin "33"
		)
		(pin "3"
		)
		(pin "19"
		)
		(pin "25"
		)
		(pin "34"
		)
		(pin "31"
		)
		(pin "23"
		)
		(pin "26"
		)
		(pin "27"
		)
		(pin "42"
		)
		(pin "41"
		)
		(pin "24"
		)
		(pin "2"
		)
		(pin "39"
		)
		(pin "28"
		)
		(pin "7"
		)
		(pin "36"
		)
		(pin "43"
		)
		(pin "38"
		)
		(pin "8"
		)
		(pin "5"
		)
		(pin "6"
		)
		(pin "37"
		)
		(pin "40"
		)
		(pin "35"
		)
		(pin "18"
		)
		(pin "21"
		)
		(pin "17"
		)
		(pin "10"
		)
		(pin "1"
		)
		(pin "16"
		)
		(pin "15"
		)
		(pin "14"
		)
		(pin "13"
		)
		(pin "12"
		)
		(pin "11"
		)
		(pin "32"
		)
		(pin "22"
		)
		(instances
			(project "com-express-7-baseboard"
				(path ""
					(reference "U39")
					(unit 1)
				)
			)
		)
	)
	(symbol
		(lib_id "antmicropower:GND")
		(at 228.6 220.98 0)
		(mirror y)
		(unit 1)
		(exclude_from_sim no)
		(in_bom yes)
		(on_board yes)
		(dnp no)
		(property "Reference" "#PWR0318"
			(at 219.71 223.52 0)
			(effects
				(font
					(size 1.27 1.27)
					(thickness 0.15)
				)
				(justify left bottom)
				(hide yes)
			)
		)
		(property "Value" "GND"
			(at 224.79 222.25 0)
			(effects
				(font
					(size 1.27 1.27)
					(thickness 0.15)
				)
			)
		)
		(property "Footprint" ""
			(at 219.71 228.6 0)
			(effects
				(font
					(size 1.27 1.27)
					(thickness 0.15)
				)
				(justify left bottom)
				(hide yes)
			)
		)
		(property "Datasheet" ""
			(at 219.71 233.68 0)
			(effects
				(font
					(size 1.27 1.27)
					(thickness 0.15)
				)
				(justify left bottom)
				(hide yes)
			)
		)
		(property "Description" ""
			(at 228.6 220.98 0)
			(effects
				(font
					(size 1.27 1.27)
				)
				(hide yes)
			)
		)
		(property "Author" "Antmicro"
			(at 219.71 228.6 0)
			(effects
				(font
					(size 1.27 1.27)
					(thickness 0.15)
				)
				(justify left bottom)
				(hide yes)
			)
		)
		(property "License" "Apache-2.0"
			(at 219.71 231.14 0)
			(effects
				(font
					(size 1.27 1.27)
					(thickness 0.15)
				)
				(justify left bottom)
				(hide yes)
			)
		)
		(pin "1"
		)
		(instances
			(project "com-express-7-baseboard"
				(path ""
					(reference "#PWR0318")
					(unit 1)
				)
			)
		)
	)
	(symbol
		(lib_id "antmicropower:GND")
		(at 170.18 167.64 0)
		(unit 1)
		(exclude_from_sim no)
		(in_bom yes)
		(on_board yes)
		(dnp no)
		(property "Reference" "#PWR0309"
			(at 179.07 170.18 0)
			(effects
				(font
					(size 1.27 1.27)
					(thickness 0.15)
				)
				(justify left bottom)
				(hide yes)
			)
		)
		(property "Value" "GND"
			(at 170.18 171.45 0)
			(effects
				(font
					(size 1.27 1.27)
					(thickness 0.15)
				)
			)
		)
		(property "Footprint" ""
			(at 179.07 175.26 0)
			(effects
				(font
					(size 1.27 1.27)
					(thickness 0.15)
				)
				(justify left bottom)
				(hide yes)
			)
		)
		(property "Datasheet" ""
			(at 179.07 180.34 0)
			(effects
				(font
					(size 1.27 1.27)
					(thickness 0.15)
				)
				(justify left bottom)
				(hide yes)
			)
		)
		(property "Description" ""
			(at 170.18 167.64 0)
			(effects
				(font
					(size 1.27 1.27)
				)
				(hide yes)
			)
		)
		(property "Author" "Antmicro"
			(at 179.07 175.26 0)
			(effects
				(font
					(size 1.27 1.27)
					(thickness 0.15)
				)
				(justify left bottom)
				(hide yes)
			)
		)
		(property "License" "Apache-2.0"
			(at 179.07 177.8 0)
			(effects
				(font
					(size 1.27 1.27)
					(thickness 0.15)
				)
				(justify left bottom)
				(hide yes)
			)
		)
		(pin "1"
		)
		(instances
			(project "com-express-7-baseboard"
				(path ""
					(reference "#PWR0309")
					(unit 1)
				)
			)
		)
	)
	(symbol
		(lib_id "antmicropower:GND")
		(at 184.15 247.65 0)
		(mirror y)
		(unit 1)
		(exclude_from_sim no)
		(in_bom yes)
		(on_board yes)
		(dnp no)
		(property "Reference" "#PWR0313"
			(at 175.26 250.19 0)
			(effects
				(font
					(size 1.27 1.27)
					(thickness 0.15)
				)
				(justify left bottom)
				(hide yes)
			)
		)
		(property "Value" "GND"
			(at 184.15 251.46 0)
			(effects
				(font
					(size 1.27 1.27)
					(thickness 0.15)
				)
			)
		)
		(property "Footprint" ""
			(at 175.26 255.27 0)
			(effects
				(font
					(size 1.27 1.27)
					(thickness 0.15)
				)
				(justify left bottom)
				(hide yes)
			)
		)
		(property "Datasheet" ""
			(at 175.26 260.35 0)
			(effects
				(font
					(size 1.27 1.27)
					(thickness 0.15)
				)
				(justify left bottom)
				(hide yes)
			)
		)
		(property "Description" ""
			(at 184.15 247.65 0)
			(effects
				(font
					(size 1.27 1.27)
				)
				(hide yes)
			)
		)
		(property "Author" "Antmicro"
			(at 175.26 255.27 0)
			(effects
				(font
					(size 1.27 1.27)
					(thickness 0.15)
				)
				(justify left bottom)
				(hide yes)
			)
		)
		(property "License" "Apache-2.0"
			(at 175.26 257.81 0)
			(effects
				(font
					(size 1.27 1.27)
					(thickness 0.15)
				)
				(justify left bottom)
				(hide yes)
			)
		)
		(pin "1"
		)
		(instances
			(project "com-express-7-baseboard"
				(path ""
					(reference "#PWR0313")
					(unit 1)
				)
			)
		)
	)
	(symbol
		(lib_id "antmicroResistors0402:R_1k_0402")
		(at 158.75 97.79 270)
		(unit 1)
		(exclude_from_sim no)
		(in_bom yes)
		(on_board yes)
		(dnp no)
		(property "Reference" "R212"
			(at 158.75 93.98 0)
			(effects
				(font
					(size 1.27 1.27)
					(thickness 0.15)
				)
				(justify right)
			)
		)
		(property "Value" "R_1k_0402"
			(at 146.05 118.11 0)
			(effects
				(font
					(size 1.27 1.27)
					(thickness 0.15)
				)
				(justify left bottom)
				(hide yes)
			)
		)
		(property "Footprint" "antmicro-footprints:R_0402_1005Metric"
			(at 143.51 118.11 0)
			(effects
				(font
					(size 1.27 1.27)
					(thickness 0.15)
				)
				(justify left bottom)
				(hide yes)
			)
		)
		(property "Datasheet" "https://www.bourns.com/docs/product-datasheets/cr.pdf"
			(at 140.97 118.11 0)
			(effects
				(font
					(size 1.27 1.27)
					(thickness 0.15)
				)
				(justify left bottom)
				(hide yes)
			)
		)
		(property "Description" ""
			(at 158.75 97.79 0)
			(effects
				(font
					(size 1.27 1.27)
				)
				(hide yes)
			)
		)
		(property "MPN" "CR0402-FX-1001GLF"
			(at 138.43 118.11 0)
			(effects
				(font
					(size 1.27 1.27)
					(thickness 0.15)
				)
				(justify left bottom)
				(hide yes)
			)
		)
		(property "Manufacturer" "Bourns"
			(at 135.89 118.11 0)
			(effects
				(font
					(size 1.27 1.27)
					(thickness 0.15)
				)
				(justify left bottom)
				(hide yes)
			)
		)
		(property "License" "Apache-2.0"
			(at 133.35 118.11 0)
			(effects
				(font
					(size 1.27 1.27)
					(thickness 0.15)
				)
				(justify left bottom)
				(hide yes)
			)
		)
		(property "Author" "Antmicro"
			(at 130.81 118.11 0)
			(effects
				(font
					(size 1.27 1.27)
					(thickness 0.15)
				)
				(justify left bottom)
				(hide yes)
			)
		)
		(property "Val" "1k"
			(at 160.02 97.79 0)
			(effects
				(font
					(size 1.27 1.27)
					(thickness 0.15)
				)
				(justify right)
			)
		)
		(property "Tolerance" "1%"
			(at 148.59 118.11 0)
			(effects
				(font
					(size 1.27 1.27)
				)
				(justify left bottom)
				(hide yes)
			)
		)
		(property "Public" "False"
			(at 128.27 118.11 0)
			(effects
				(font
					(size 1.27 1.27)
				)
				(justify left bottom)
				(hide yes)
			)
		)
		(pin "1"
		)
		(pin "2"
		)
		(instances
			(project "com-express-7-baseboard"
				(path ""
					(reference "R212")
					(unit 1)
				)
			)
		)
	)
	(symbol
		(lib_id "antmicroResistors0402:R_1k_0402")
		(at 247.65 251.46 270)
		(mirror x)
		(unit 1)
		(exclude_from_sim no)
		(in_bom yes)
		(on_board yes)
		(dnp yes)
		(property "Reference" "R230"
			(at 247.65 255.27 0)
			(effects
				(font
					(size 1.27 1.27)
					(thickness 0.15)
				)
				(justify right)
			)
		)
		(property "Value" "R_1k_0402"
			(at 234.95 231.14 0)
			(effects
				(font
					(size 1.27 1.27)
					(thickness 0.15)
				)
				(justify left bottom)
				(hide yes)
			)
		)
		(property "Footprint" "antmicro-footprints:R_0402_1005Metric"
			(at 232.41 231.14 0)
			(effects
				(font
					(size 1.27 1.27)
					(thickness 0.15)
				)
				(justify left bottom)
				(hide yes)
			)
		)
		(property "Datasheet" "https://www.bourns.com/docs/product-datasheets/cr.pdf"
			(at 229.87 231.14 0)
			(effects
				(font
					(size 1.27 1.27)
					(thickness 0.15)
				)
				(justify left bottom)
				(hide yes)
			)
		)
		(property "Description" ""
			(at 247.65 251.46 0)
			(effects
				(font
					(size 1.27 1.27)
				)
				(hide yes)
			)
		)
		(property "MPN" "CR0402-FX-1001GLF"
			(at 227.33 231.14 0)
			(effects
				(font
					(size 1.27 1.27)
					(thickness 0.15)
				)
				(justify left bottom)
				(hide yes)
			)
		)
		(property "Manufacturer" "Bourns"
			(at 224.79 231.14 0)
			(effects
				(font
					(size 1.27 1.27)
					(thickness 0.15)
				)
				(justify left bottom)
				(hide yes)
			)
		)
		(property "License" "Apache-2.0"
			(at 222.25 231.14 0)
			(effects
				(font
					(size 1.27 1.27)
					(thickness 0.15)
				)
				(justify left bottom)
				(hide yes)
			)
		)
		(property "Author" "Antmicro"
			(at 219.71 231.14 0)
			(effects
				(font
					(size 1.27 1.27)
					(thickness 0.15)
				)
				(justify left bottom)
				(hide yes)
			)
		)
		(property "Val" "1k"
			(at 248.92 251.46 0)
			(effects
				(font
					(size 1.27 1.27)
					(thickness 0.15)
				)
				(justify right)
			)
		)
		(property "Tolerance" "1%"
			(at 237.49 231.14 0)
			(effects
				(font
					(size 1.27 1.27)
				)
				(justify left bottom)
				(hide yes)
			)
		)
		(property "Public" "False"
			(at 217.17 231.14 0)
			(effects
				(font
					(size 1.27 1.27)
				)
				(justify left bottom)
				(hide yes)
			)
		)
		(pin "1"
		)
		(pin "2"
		)
		(instances
			(project "com-express-7-baseboard"
				(path ""
					(reference "R230")
					(unit 1)
				)
			)
		)
	)
	(symbol
		(lib_id "antmicroResistors0402:R_1k_0402")
		(at 247.65 222.25 90)
		(mirror x)
		(unit 1)
		(exclude_from_sim no)
		(in_bom yes)
		(on_board yes)
		(dnp no)
		(property "Reference" "R229"
			(at 247.65 218.44 0)
			(effects
				(font
					(size 1.27 1.27)
					(thickness 0.15)
				)
				(justify right)
			)
		)
		(property "Value" "R_1k_0402"
			(at 260.35 242.57 0)
			(effects
				(font
					(size 1.27 1.27)
					(thickness 0.15)
				)
				(justify left bottom)
				(hide yes)
			)
		)
		(property "Footprint" "antmicro-footprints:R_0402_1005Metric"
			(at 262.89 242.57 0)
			(effects
				(font
					(size 1.27 1.27)
					(thickness 0.15)
				)
				(justify left bottom)
				(hide yes)
			)
		)
		(property "Datasheet" "https://www.bourns.com/docs/product-datasheets/cr.pdf"
			(at 265.43 242.57 0)
			(effects
				(font
					(size 1.27 1.27)
					(thickness 0.15)
				)
				(justify left bottom)
				(hide yes)
			)
		)
		(property "Description" ""
			(at 247.65 222.25 0)
			(effects
				(font
					(size 1.27 1.27)
				)
				(hide yes)
			)
		)
		(property "MPN" "CR0402-FX-1001GLF"
			(at 267.97 242.57 0)
			(effects
				(font
					(size 1.27 1.27)
					(thickness 0.15)
				)
				(justify left bottom)
				(hide yes)
			)
		)
		(property "Manufacturer" "Bourns"
			(at 270.51 242.57 0)
			(effects
				(font
					(size 1.27 1.27)
					(thickness 0.15)
				)
				(justify left bottom)
				(hide yes)
			)
		)
		(property "License" "Apache-2.0"
			(at 273.05 242.57 0)
			(effects
				(font
					(size 1.27 1.27)
					(thickness 0.15)
				)
				(justify left bottom)
				(hide yes)
			)
		)
		(property "Author" "Antmicro"
			(at 275.59 242.57 0)
			(effects
				(font
					(size 1.27 1.27)
					(thickness 0.15)
				)
				(justify left bottom)
				(hide yes)
			)
		)
		(property "Val" "1k"
			(at 246.38 222.25 0)
			(effects
				(font
					(size 1.27 1.27)
					(thickness 0.15)
				)
				(justify right)
			)
		)
		(property "Tolerance" "1%"
			(at 257.81 242.57 0)
			(effects
				(font
					(size 1.27 1.27)
				)
				(justify left bottom)
				(hide yes)
			)
		)
		(property "Public" "False"
			(at 278.13 242.57 0)
			(effects
				(font
					(size 1.27 1.27)
				)
				(justify left bottom)
				(hide yes)
			)
		)
		(pin "1"
		)
		(pin "2"
		)
		(instances
			(project "com-express-7-baseboard"
				(path ""
					(reference "R229")
					(unit 1)
				)
			)
		)
	)
	(symbol
		(lib_id "antmicropower:GND")
		(at 167.64 45.72 0)
		(unit 1)
		(exclude_from_sim no)
		(in_bom yes)
		(on_board yes)
		(dnp no)
		(property "Reference" "#PWR0307"
			(at 176.53 48.26 0)
			(effects
				(font
					(size 1.27 1.27)
					(thickness 0.15)
				)
				(justify left bottom)
				(hide yes)
			)
		)
		(property "Value" "GND"
			(at 167.64 49.53 0)
			(effects
				(font
					(size 1.27 1.27)
					(thickness 0.15)
				)
			)
		)
		(property "Footprint" ""
			(at 176.53 53.34 0)
			(effects
				(font
					(size 1.27 1.27)
					(thickness 0.15)
				)
				(justify left bottom)
				(hide yes)
			)
		)
		(property "Datasheet" ""
			(at 176.53 58.42 0)
			(effects
				(font
					(size 1.27 1.27)
					(thickness 0.15)
				)
				(justify left bottom)
				(hide yes)
			)
		)
		(property "Description" ""
			(at 167.64 45.72 0)
			(effects
				(font
					(size 1.27 1.27)
				)
				(hide yes)
			)
		)
		(property "Author" "Antmicro"
			(at 176.53 53.34 0)
			(effects
				(font
					(size 1.27 1.27)
					(thickness 0.15)
				)
				(justify left bottom)
				(hide yes)
			)
		)
		(property "License" "Apache-2.0"
			(at 176.53 55.88 0)
			(effects
				(font
					(size 1.27 1.27)
					(thickness 0.15)
				)
				(justify left bottom)
				(hide yes)
			)
		)
		(pin "1"
		)
		(instances
			(project "com-express-7-baseboard"
				(path ""
					(reference "#PWR0307")
					(unit 1)
				)
			)
		)
	)
	(symbol
		(lib_id "antmicroCapacitors0402:C_220n_0402")
		(at 152.4 201.93 0)
		(unit 1)
		(exclude_from_sim no)
		(in_bom yes)
		(on_board yes)
		(dnp no)
		(property "Reference" "C125"
			(at 151.13 203.2 0)
			(effects
				(font
					(size 1.27 1.27)
					(thickness 0.15)
				)
			)
		)
		(property "Value" "C_220n_0402"
			(at 172.72 212.09 0)
			(effects
				(font
					(size 1.27 1.27)
					(thickness 0.15)
				)
				(justify left bottom)
				(hide yes)
			)
		)
		(property "Footprint" "antmicro-footprints:C_0402_1005Metric"
			(at 172.72 214.63 0)
			(effects
				(font
					(size 1.27 1.27)
					(thickness 0.15)
				)
				(justify left bottom)
				(hide yes)
			)
		)
		(property "Datasheet" "https://www.yageo.com/en/Chart/Download/pdf/CC0402KRX5R6BB224"
			(at 172.72 217.17 0)
			(effects
				(font
					(size 1.27 1.27)
					(thickness 0.15)
				)
				(justify left bottom)
				(hide yes)
			)
		)
		(property "Description" ""
			(at 152.4 201.93 0)
			(effects
				(font
					(size 1.27 1.27)
				)
				(hide yes)
			)
		)
		(property "MPN" "CC0402KRX5R6BB224"
			(at 172.72 219.71 0)
			(effects
				(font
					(size 1.27 1.27)
					(thickness 0.15)
				)
				(justify left bottom)
				(hide yes)
			)
		)
		(property "Manufacturer" "YAGEO"
			(at 172.72 222.25 0)
			(effects
				(font
					(size 1.27 1.27)
					(thickness 0.15)
				)
				(justify left bottom)
				(hide yes)
			)
		)
		(property "License" "Apache-2.0"
			(at 172.72 224.79 0)
			(effects
				(font
					(size 1.27 1.27)
					(thickness 0.15)
				)
				(justify left bottom)
				(hide yes)
			)
		)
		(property "Author" "Antmicro"
			(at 172.72 227.33 0)
			(effects
				(font
					(size 1.27 1.27)
					(thickness 0.15)
				)
				(justify left bottom)
				(hide yes)
			)
		)
		(property "Val" "220n"
			(at 158.75 203.2 0)
			(effects
				(font
					(size 1.27 1.27)
					(thickness 0.15)
				)
			)
		)
		(property "Voltage" ""
			(at 172.72 229.87 0)
			(effects
				(font
					(size 1.27 1.27)
				)
				(justify left bottom)
				(hide yes)
			)
		)
		(property "Dielectric" ""
			(at 172.72 232.41 0)
			(effects
				(font
					(size 1.27 1.27)
				)
				(justify left bottom)
				(hide yes)
			)
		)
		(property "Public" "False"
			(at 172.72 234.95 0)
			(effects
				(font
					(size 1.27 1.27)
				)
				(justify left bottom)
				(hide yes)
			)
		)
		(pin "1"
		)
		(pin "2"
		)
		(instances
			(project "com-express-7-baseboard"
				(path ""
					(reference "C125")
					(unit 1)
				)
			)
		)
	)
	(symbol
		(lib_id "antmicropower:GND")
		(at 179.07 152.4 0)
		(unit 1)
		(exclude_from_sim no)
		(in_bom yes)
		(on_board yes)
		(dnp no)
		(property "Reference" "#PWR0311"
			(at 187.96 154.94 0)
			(effects
				(font
					(size 1.27 1.27)
					(thickness 0.15)
				)
				(justify left bottom)
				(hide yes)
			)
		)
		(property "Value" "GND"
			(at 179.07 156.21 0)
			(effects
				(font
					(size 1.27 1.27)
					(thickness 0.15)
				)
			)
		)
		(property "Footprint" ""
			(at 187.96 160.02 0)
			(effects
				(font
					(size 1.27 1.27)
					(thickness 0.15)
				)
				(justify left bottom)
				(hide yes)
			)
		)
		(property "Datasheet" ""
			(at 187.96 165.1 0)
			(effects
				(font
					(size 1.27 1.27)
					(thickness 0.15)
				)
				(justify left bottom)
				(hide yes)
			)
		)
		(property "Description" ""
			(at 179.07 152.4 0)
			(effects
				(font
					(size 1.27 1.27)
				)
				(hide yes)
			)
		)
		(property "Author" "Antmicro"
			(at 187.96 160.02 0)
			(effects
				(font
					(size 1.27 1.27)
					(thickness 0.15)
				)
				(justify left bottom)
				(hide yes)
			)
		)
		(property "License" "Apache-2.0"
			(at 187.96 162.56 0)
			(effects
				(font
					(size 1.27 1.27)
					(thickness 0.15)
				)
				(justify left bottom)
				(hide yes)
			)
		)
		(pin "1"
		)
		(instances
			(project "com-express-7-baseboard"
				(path ""
					(reference "#PWR0311")
					(unit 1)
				)
			)
		)
	)
)
